G04*
G04 #@! TF.GenerationSoftware,Altium Limited,Altium Designer,23.6.0 (18)*
G04*
G04 Layer_Color=65535*
%FSLAX44Y44*%
%MOMM*%
G71*
G04*
G04 #@! TF.SameCoordinates,B62FFF2A-40BB-47C2-B022-6C0D6E2DF31E*
G04*
G04*
G04 #@! TF.FilePolarity,Positive*
G04*
G01*
G75*
%ADD10C,0.2500*%
%ADD11C,0.1778*%
%ADD12C,0.1270*%
%ADD13C,0.2000*%
%ADD14C,0.0762*%
%ADD15C,0.1524*%
%ADD16C,0.1000*%
%ADD17C,0.2540*%
%ADD18C,0.1780*%
%ADD19R,0.1010X0.0691*%
%ADD20R,0.0691X0.1010*%
%ADD21R,0.4500X3.4755*%
G36*
X15277Y138147D02*
X16445D01*
Y137549D01*
X15277D01*
Y135431D01*
X14728D01*
X11576Y137661D01*
Y138147D01*
X14728D01*
Y138808D01*
X15277D01*
Y138147D01*
D02*
G37*
G36*
X16445Y133503D02*
X12639D01*
X12646Y133496D01*
X12674Y133461D01*
X12716Y133419D01*
X12765Y133348D01*
X12829Y133271D01*
X12899Y133172D01*
X12976Y133060D01*
X13054Y132933D01*
Y132926D01*
X13061Y132919D01*
X13089Y132877D01*
X13124Y132807D01*
X13166Y132722D01*
X13216Y132624D01*
X13265Y132518D01*
X13314Y132413D01*
X13356Y132307D01*
X12779D01*
Y132314D01*
X12765Y132328D01*
X12758Y132356D01*
X12737Y132391D01*
X12716Y132434D01*
X12688Y132483D01*
X12617Y132603D01*
X12540Y132743D01*
X12442Y132884D01*
X12329Y133032D01*
X12209Y133179D01*
X12202Y133186D01*
X12195Y133194D01*
X12174Y133215D01*
X12153Y133243D01*
X12083Y133306D01*
X11998Y133391D01*
X11900Y133475D01*
X11787Y133566D01*
X11675Y133644D01*
X11555Y133714D01*
Y134101D01*
X16445D01*
Y133503D01*
D02*
G37*
G36*
Y130668D02*
X15432Y130027D01*
X15425D01*
X15411Y130013D01*
X15390Y129999D01*
X15361Y129978D01*
X15284Y129929D01*
X15186Y129866D01*
X15080Y129788D01*
X14967Y129711D01*
X14862Y129633D01*
X14763Y129563D01*
X14756Y129556D01*
X14728Y129535D01*
X14686Y129500D01*
X14637Y129450D01*
X14531Y129345D01*
X14482Y129289D01*
X14440Y129232D01*
X14433Y129225D01*
X14426Y129211D01*
X14412Y129183D01*
X14390Y129141D01*
X14369Y129099D01*
X14348Y129049D01*
X14313Y128937D01*
Y128930D01*
X14306Y128916D01*
Y128888D01*
X14299Y128852D01*
X14292Y128803D01*
Y128747D01*
X14285Y128670D01*
Y127839D01*
X16445D01*
Y127192D01*
X11576D01*
Y129450D01*
X11583Y129507D01*
Y129570D01*
X11590Y129718D01*
X11611Y129873D01*
X11632Y130041D01*
X11668Y130196D01*
X11689Y130274D01*
X11710Y130337D01*
Y130344D01*
X11717Y130351D01*
X11738Y130393D01*
X11766Y130457D01*
X11815Y130534D01*
X11879Y130618D01*
X11963Y130710D01*
X12062Y130794D01*
X12174Y130879D01*
X12181D01*
X12188Y130886D01*
X12230Y130914D01*
X12301Y130942D01*
X12392Y130984D01*
X12498Y131019D01*
X12624Y131055D01*
X12758Y131076D01*
X12906Y131083D01*
X12913D01*
X12927D01*
X12955D01*
X12990Y131076D01*
X13040D01*
X13089Y131069D01*
X13209Y131040D01*
X13349Y130998D01*
X13497Y130942D01*
X13645Y130858D01*
X13715Y130801D01*
X13785Y130745D01*
X13792Y130738D01*
X13800Y130731D01*
X13821Y130710D01*
X13842Y130682D01*
X13870Y130646D01*
X13898Y130604D01*
X13933Y130548D01*
X13975Y130492D01*
X14010Y130421D01*
X14046Y130344D01*
X14088Y130260D01*
X14123Y130168D01*
X14151Y130063D01*
X14186Y129957D01*
X14208Y129837D01*
X14229Y129711D01*
X14236Y129725D01*
X14250Y129753D01*
X14278Y129795D01*
X14306Y129852D01*
X14383Y129978D01*
X14433Y130041D01*
X14475Y130098D01*
X14489Y130112D01*
X14524Y130147D01*
X14580Y130203D01*
X14651Y130274D01*
X14749Y130351D01*
X14855Y130442D01*
X14981Y130534D01*
X15122Y130632D01*
X16445Y131470D01*
Y130668D01*
D02*
G37*
G36*
X22869Y138829D02*
X22925Y138822D01*
X22989Y138815D01*
X23066Y138801D01*
X23143Y138787D01*
X23326Y138745D01*
X23516Y138674D01*
X23615Y138632D01*
X23706Y138576D01*
X23805Y138520D01*
X23896Y138449D01*
X23903Y138442D01*
X23924Y138428D01*
X23952Y138400D01*
X23988Y138365D01*
X24030Y138315D01*
X24086Y138259D01*
X24135Y138189D01*
X24192Y138111D01*
X24248Y138027D01*
X24297Y137929D01*
X24346Y137823D01*
X24396Y137711D01*
X24431Y137591D01*
X24459Y137457D01*
X24480Y137317D01*
X24487Y137169D01*
Y137105D01*
X24480Y137056D01*
X24473Y137000D01*
X24466Y136937D01*
X24459Y136859D01*
X24438Y136782D01*
X24396Y136606D01*
X24332Y136430D01*
X24290Y136339D01*
X24241Y136247D01*
X24185Y136163D01*
X24121Y136078D01*
X24114Y136071D01*
X24107Y136057D01*
X24079Y136043D01*
X24051Y136015D01*
X24016Y135980D01*
X23974Y135944D01*
X23917Y135902D01*
X23854Y135867D01*
X23791Y135825D01*
X23713Y135783D01*
X23544Y135705D01*
X23347Y135642D01*
X23242Y135621D01*
X23129Y135607D01*
X23080Y136233D01*
X23087D01*
X23101D01*
X23122Y136240D01*
X23157Y136247D01*
X23235Y136268D01*
X23340Y136296D01*
X23446Y136339D01*
X23565Y136395D01*
X23671Y136465D01*
X23770Y136550D01*
X23777Y136564D01*
X23805Y136592D01*
X23840Y136648D01*
X23882Y136726D01*
X23924Y136810D01*
X23960Y136915D01*
X23988Y137035D01*
X23995Y137169D01*
Y137211D01*
X23988Y137239D01*
X23981Y137324D01*
X23952Y137422D01*
X23917Y137542D01*
X23861Y137661D01*
X23777Y137788D01*
X23727Y137844D01*
X23671Y137900D01*
X23664Y137907D01*
X23657Y137914D01*
X23636Y137929D01*
X23615Y137950D01*
X23537Y137999D01*
X23439Y138055D01*
X23319Y138104D01*
X23172Y138154D01*
X22996Y138189D01*
X22904Y138203D01*
X22806D01*
X22799D01*
X22785D01*
X22756D01*
X22721Y138196D01*
X22679D01*
X22630Y138189D01*
X22517Y138168D01*
X22383Y138133D01*
X22250Y138083D01*
X22123Y138013D01*
X22004Y137914D01*
X21997D01*
X21989Y137900D01*
X21954Y137865D01*
X21905Y137802D01*
X21849Y137718D01*
X21799Y137605D01*
X21750Y137478D01*
X21715Y137331D01*
X21701Y137246D01*
Y137112D01*
X21708Y137056D01*
X21715Y136986D01*
X21736Y136901D01*
X21757Y136817D01*
X21792Y136726D01*
X21835Y136634D01*
X21842Y136627D01*
X21856Y136599D01*
X21891Y136557D01*
X21926Y136500D01*
X21975Y136444D01*
X22039Y136388D01*
X22102Y136324D01*
X22179Y136275D01*
X22102Y135712D01*
X19597Y136184D01*
Y138604D01*
X20167D01*
Y136655D01*
X21483Y136395D01*
X21476Y136402D01*
X21469Y136416D01*
X21455Y136437D01*
X21434Y136472D01*
X21412Y136514D01*
X21384Y136564D01*
X21328Y136676D01*
X21272Y136817D01*
X21223Y136972D01*
X21187Y137141D01*
X21173Y137225D01*
Y137380D01*
X21180Y137422D01*
X21187Y137478D01*
X21194Y137542D01*
X21209Y137612D01*
X21230Y137689D01*
X21279Y137858D01*
X21314Y137950D01*
X21363Y138041D01*
X21412Y138133D01*
X21469Y138224D01*
X21539Y138308D01*
X21616Y138393D01*
X21624Y138400D01*
X21638Y138414D01*
X21659Y138435D01*
X21694Y138463D01*
X21743Y138498D01*
X21792Y138534D01*
X21856Y138576D01*
X21926Y138618D01*
X22004Y138653D01*
X22088Y138695D01*
X22186Y138731D01*
X22285Y138766D01*
X22390Y138794D01*
X22510Y138815D01*
X22630Y138829D01*
X22756Y138836D01*
X22763D01*
X22785D01*
X22820D01*
X22869Y138829D01*
D02*
G37*
G36*
X24403Y133475D02*
X20596D01*
X20603Y133468D01*
X20631Y133433D01*
X20674Y133391D01*
X20723Y133320D01*
X20786Y133243D01*
X20857Y133144D01*
X20934Y133032D01*
X21012Y132905D01*
Y132898D01*
X21019Y132891D01*
X21047Y132849D01*
X21082Y132778D01*
X21124Y132694D01*
X21173Y132595D01*
X21223Y132490D01*
X21272Y132384D01*
X21314Y132279D01*
X20737D01*
Y132286D01*
X20723Y132300D01*
X20716Y132328D01*
X20695Y132363D01*
X20674Y132406D01*
X20646Y132455D01*
X20575Y132574D01*
X20498Y132715D01*
X20399Y132856D01*
X20287Y133004D01*
X20167Y133151D01*
X20160Y133158D01*
X20153Y133165D01*
X20132Y133186D01*
X20111Y133215D01*
X20041Y133278D01*
X19956Y133362D01*
X19858Y133447D01*
X19745Y133538D01*
X19632Y133616D01*
X19513Y133686D01*
Y134073D01*
X24403D01*
Y133475D01*
D02*
G37*
G36*
Y130639D02*
X23390Y129999D01*
X23382D01*
X23368Y129985D01*
X23347Y129971D01*
X23319Y129950D01*
X23242Y129901D01*
X23143Y129837D01*
X23038Y129760D01*
X22925Y129683D01*
X22820Y129605D01*
X22721Y129535D01*
X22714Y129528D01*
X22686Y129507D01*
X22644Y129472D01*
X22594Y129422D01*
X22489Y129317D01*
X22440Y129261D01*
X22397Y129204D01*
X22390Y129197D01*
X22383Y129183D01*
X22369Y129155D01*
X22348Y129113D01*
X22327Y129071D01*
X22306Y129021D01*
X22271Y128909D01*
Y128902D01*
X22264Y128888D01*
Y128859D01*
X22257Y128824D01*
X22250Y128775D01*
Y128719D01*
X22243Y128641D01*
Y127811D01*
X24403D01*
Y127164D01*
X19534D01*
Y129422D01*
X19541Y129479D01*
Y129542D01*
X19548Y129690D01*
X19569Y129844D01*
X19590Y130013D01*
X19625Y130168D01*
X19647Y130246D01*
X19668Y130309D01*
Y130316D01*
X19675Y130323D01*
X19696Y130365D01*
X19724Y130428D01*
X19773Y130506D01*
X19836Y130590D01*
X19921Y130682D01*
X20019Y130766D01*
X20132Y130851D01*
X20139D01*
X20146Y130858D01*
X20188Y130886D01*
X20259Y130914D01*
X20350Y130956D01*
X20456Y130991D01*
X20582Y131026D01*
X20716Y131048D01*
X20864Y131055D01*
X20871D01*
X20885D01*
X20913D01*
X20948Y131048D01*
X20997D01*
X21047Y131040D01*
X21166Y131012D01*
X21307Y130970D01*
X21455Y130914D01*
X21602Y130829D01*
X21673Y130773D01*
X21743Y130717D01*
X21750Y130710D01*
X21757Y130703D01*
X21778Y130682D01*
X21799Y130654D01*
X21828Y130618D01*
X21856Y130576D01*
X21891Y130520D01*
X21933Y130464D01*
X21968Y130393D01*
X22004Y130316D01*
X22046Y130231D01*
X22081Y130140D01*
X22109Y130034D01*
X22144Y129929D01*
X22165Y129809D01*
X22186Y129683D01*
X22194Y129697D01*
X22208Y129725D01*
X22236Y129767D01*
X22264Y129823D01*
X22341Y129950D01*
X22390Y130013D01*
X22433Y130070D01*
X22447Y130084D01*
X22482Y130119D01*
X22538Y130175D01*
X22609Y130246D01*
X22707Y130323D01*
X22813Y130414D01*
X22939Y130506D01*
X23080Y130604D01*
X24403Y131442D01*
Y130639D01*
D02*
G37*
G36*
X41804Y160202D02*
X41917Y160188D01*
X42058Y160174D01*
X42213Y160145D01*
X42368Y160117D01*
X42735Y160019D01*
X43101Y159878D01*
X43284Y159793D01*
X43468Y159694D01*
X43637Y159567D01*
X43792Y159426D01*
X43806Y159412D01*
X43834Y159398D01*
X43862Y159342D01*
X43919Y159285D01*
X43989Y159215D01*
X44060Y159116D01*
X44130Y159018D01*
X44215Y158891D01*
X44356Y158623D01*
X44497Y158285D01*
X44553Y158115D01*
X44581Y157918D01*
X44610Y157721D01*
X44624Y157509D01*
Y157481D01*
Y157411D01*
X44610Y157298D01*
X44595Y157143D01*
X44567Y156974D01*
X44511Y156776D01*
X44454Y156565D01*
X44370Y156353D01*
X44356Y156325D01*
X44328Y156255D01*
X44271Y156142D01*
X44187Y155987D01*
X44074Y155818D01*
X43933Y155606D01*
X43764Y155395D01*
X43566Y155155D01*
X43538Y155127D01*
X43468Y155042D01*
X43397Y154972D01*
X43327Y154901D01*
X43242Y154817D01*
X43129Y154704D01*
X43017Y154591D01*
X42876Y154464D01*
X42735Y154323D01*
X42565Y154168D01*
X42382Y154013D01*
X42185Y153830D01*
X41959Y153647D01*
X41734Y153449D01*
X41720Y153435D01*
X41691Y153407D01*
X41635Y153365D01*
X41565Y153308D01*
X41480Y153224D01*
X41381Y153139D01*
X41156Y152956D01*
X40916Y152745D01*
X40691Y152533D01*
X40493Y152350D01*
X40409Y152279D01*
X40338Y152209D01*
X40324Y152195D01*
X40282Y152152D01*
X40225Y152096D01*
X40155Y152011D01*
X40084Y151913D01*
X40000Y151814D01*
X39831Y151574D01*
X44638D01*
Y150419D01*
X38167D01*
Y150433D01*
Y150489D01*
Y150574D01*
X38181Y150686D01*
X38195Y150813D01*
X38224Y150954D01*
X38252Y151095D01*
X38308Y151250D01*
Y151264D01*
X38322Y151278D01*
X38351Y151363D01*
X38407Y151490D01*
X38491Y151659D01*
X38604Y151856D01*
X38745Y152082D01*
X38900Y152308D01*
X39098Y152547D01*
Y152561D01*
X39126Y152575D01*
X39196Y152660D01*
X39323Y152787D01*
X39506Y152970D01*
X39718Y153181D01*
X39986Y153435D01*
X40310Y153717D01*
X40662Y154013D01*
X40676Y154027D01*
X40733Y154070D01*
X40817Y154140D01*
X40916Y154225D01*
X41043Y154337D01*
X41198Y154464D01*
X41353Y154605D01*
X41536Y154760D01*
X41889Y155099D01*
X42241Y155437D01*
X42410Y155606D01*
X42565Y155775D01*
X42706Y155930D01*
X42819Y156086D01*
Y156100D01*
X42847Y156114D01*
X42876Y156156D01*
X42904Y156212D01*
X43003Y156367D01*
X43115Y156551D01*
X43214Y156776D01*
X43313Y157016D01*
X43369Y157284D01*
X43397Y157537D01*
Y157552D01*
Y157566D01*
X43383Y157650D01*
X43369Y157791D01*
X43327Y157946D01*
X43270Y158144D01*
X43172Y158341D01*
X43045Y158538D01*
X42876Y158736D01*
X42847Y158764D01*
X42777Y158820D01*
X42678Y158891D01*
X42523Y158989D01*
X42326Y159074D01*
X42100Y159159D01*
X41832Y159215D01*
X41536Y159229D01*
X41452D01*
X41395Y159215D01*
X41226Y159201D01*
X41029Y159159D01*
X40817Y159102D01*
X40578Y159003D01*
X40352Y158877D01*
X40141Y158708D01*
X40113Y158679D01*
X40056Y158609D01*
X39972Y158496D01*
X39887Y158327D01*
X39788Y158130D01*
X39704Y157876D01*
X39647Y157594D01*
X39619Y157270D01*
X38393Y157396D01*
Y157411D01*
X38407Y157453D01*
Y157523D01*
X38421Y157622D01*
X38449Y157735D01*
X38477Y157862D01*
X38520Y158017D01*
X38562Y158172D01*
X38675Y158510D01*
X38844Y158848D01*
X38943Y159018D01*
X39069Y159187D01*
X39196Y159342D01*
X39337Y159483D01*
X39351Y159497D01*
X39380Y159511D01*
X39422Y159553D01*
X39492Y159596D01*
X39577Y159652D01*
X39676Y159708D01*
X39788Y159779D01*
X39929Y159849D01*
X40084Y159920D01*
X40254Y159990D01*
X40437Y160047D01*
X40634Y160103D01*
X40846Y160145D01*
X41071Y160188D01*
X41311Y160202D01*
X41565Y160216D01*
X41706D01*
X41804Y160202D01*
D02*
G37*
G36*
X32655Y160329D02*
X32782D01*
X32909Y160315D01*
X33078Y160286D01*
X33247Y160258D01*
X33614Y160188D01*
X34037Y160075D01*
X34446Y159906D01*
X34657Y159807D01*
X34869Y159694D01*
X34883Y159680D01*
X34911Y159666D01*
X34967Y159624D01*
X35052Y159581D01*
X35136Y159511D01*
X35249Y159426D01*
X35489Y159229D01*
X35742Y158975D01*
X36024Y158665D01*
X36292Y158299D01*
X36518Y157890D01*
Y157876D01*
X36546Y157833D01*
X36574Y157777D01*
X36602Y157692D01*
X36659Y157580D01*
X36701Y157453D01*
X36758Y157298D01*
X36814Y157129D01*
X36856Y156945D01*
X36913Y156748D01*
X36969Y156537D01*
X37011Y156311D01*
X37068Y155818D01*
X37096Y155296D01*
Y155282D01*
Y155240D01*
Y155183D01*
Y155099D01*
X37082Y154986D01*
Y154859D01*
X37068Y154718D01*
X37054Y154577D01*
X37011Y154239D01*
X36941Y153872D01*
X36856Y153492D01*
X36729Y153125D01*
Y153111D01*
X36715Y153083D01*
X36687Y153026D01*
X36659Y152970D01*
X36617Y152885D01*
X36574Y152787D01*
X36462Y152561D01*
X36306Y152293D01*
X36109Y152011D01*
X35884Y151729D01*
X35630Y151448D01*
X35644D01*
X35672Y151419D01*
X35714Y151391D01*
X35785Y151349D01*
X35855Y151292D01*
X35954Y151236D01*
X36165Y151109D01*
X36419Y150954D01*
X36701Y150799D01*
X36997Y150672D01*
X37279Y150545D01*
X36899Y149657D01*
X36884D01*
X36856Y149671D01*
X36800Y149699D01*
X36715Y149728D01*
X36617Y149770D01*
X36504Y149826D01*
X36377Y149883D01*
X36236Y149953D01*
X35926Y150122D01*
X35573Y150320D01*
X35193Y150574D01*
X34798Y150856D01*
X34784D01*
X34756Y150827D01*
X34685Y150799D01*
X34615Y150757D01*
X34502Y150715D01*
X34389Y150658D01*
X34248Y150616D01*
X34093Y150559D01*
X33924Y150503D01*
X33741Y150447D01*
X33332Y150348D01*
X32881Y150278D01*
X32641Y150263D01*
X32402Y150249D01*
X32275D01*
X32176Y150263D01*
X32063D01*
X31922Y150278D01*
X31767Y150306D01*
X31598Y150334D01*
X31232Y150404D01*
X30823Y150517D01*
X30400Y150672D01*
X30202Y150771D01*
X29991Y150884D01*
X29977Y150898D01*
X29949Y150912D01*
X29892Y150954D01*
X29822Y150996D01*
X29723Y151067D01*
X29625Y151152D01*
X29385Y151349D01*
X29117Y151603D01*
X28849Y151913D01*
X28581Y152265D01*
X28342Y152674D01*
Y152688D01*
X28313Y152730D01*
X28285Y152787D01*
X28257Y152871D01*
X28215Y152984D01*
X28158Y153111D01*
X28102Y153266D01*
X28060Y153435D01*
X28003Y153618D01*
X27947Y153816D01*
X27905Y154027D01*
X27848Y154267D01*
X27792Y154760D01*
X27764Y155282D01*
Y155296D01*
Y155352D01*
Y155423D01*
X27778Y155522D01*
Y155648D01*
X27792Y155803D01*
X27806Y155973D01*
X27834Y156156D01*
X27905Y156565D01*
X28003Y157002D01*
X28144Y157467D01*
X28342Y157918D01*
X28356Y157932D01*
X28370Y157975D01*
X28398Y158031D01*
X28454Y158115D01*
X28511Y158214D01*
X28581Y158327D01*
X28779Y158595D01*
X29004Y158877D01*
X29300Y159173D01*
X29625Y159469D01*
X30005Y159722D01*
X30019Y159737D01*
X30062Y159751D01*
X30118Y159779D01*
X30202Y159821D01*
X30301Y159864D01*
X30414Y159920D01*
X30555Y159976D01*
X30710Y160033D01*
X30893Y160089D01*
X31076Y160145D01*
X31485Y160244D01*
X31936Y160315D01*
X32176Y160343D01*
X32557D01*
X32655Y160329D01*
D02*
G37*
G36*
X213000Y223274D02*
X212986D01*
X212931D01*
X212847D01*
X212736Y223288D01*
X212612Y223302D01*
X212473Y223330D01*
X212334Y223358D01*
X212182Y223413D01*
X212168D01*
X212154Y223427D01*
X212071Y223455D01*
X211946Y223510D01*
X211780Y223593D01*
X211585Y223704D01*
X211364Y223843D01*
X211142Y223996D01*
X210906Y224190D01*
X210892D01*
X210878Y224217D01*
X210795Y224287D01*
X210670Y224412D01*
X210490Y224592D01*
X210282Y224800D01*
X210032Y225063D01*
X209755Y225382D01*
X209464Y225729D01*
X209450Y225743D01*
X209408Y225798D01*
X209339Y225882D01*
X209256Y225979D01*
X209145Y226104D01*
X209020Y226256D01*
X208881Y226409D01*
X208729Y226589D01*
X208396Y226936D01*
X208063Y227282D01*
X207896Y227449D01*
X207730Y227601D01*
X207577Y227740D01*
X207425Y227851D01*
X207411D01*
X207397Y227879D01*
X207356Y227906D01*
X207300Y227934D01*
X207148Y228031D01*
X206967Y228142D01*
X206745Y228239D01*
X206510Y228336D01*
X206246Y228392D01*
X205996Y228420D01*
X205983D01*
X205969D01*
X205886Y228406D01*
X205747Y228392D01*
X205594Y228350D01*
X205400Y228295D01*
X205206Y228198D01*
X205012Y228073D01*
X204818Y227906D01*
X204790Y227879D01*
X204734Y227809D01*
X204665Y227712D01*
X204568Y227560D01*
X204485Y227366D01*
X204402Y227144D01*
X204346Y226880D01*
X204332Y226589D01*
Y226506D01*
X204346Y226450D01*
X204360Y226284D01*
X204402Y226090D01*
X204457Y225882D01*
X204554Y225646D01*
X204679Y225424D01*
X204845Y225216D01*
X204873Y225188D01*
X204942Y225133D01*
X205053Y225050D01*
X205220Y224966D01*
X205414Y224869D01*
X205664Y224786D01*
X205941Y224731D01*
X206260Y224703D01*
X206135Y223496D01*
X206121D01*
X206080Y223510D01*
X206010D01*
X205913Y223524D01*
X205802Y223552D01*
X205678Y223580D01*
X205525Y223621D01*
X205372Y223663D01*
X205040Y223774D01*
X204707Y223940D01*
X204540Y224037D01*
X204374Y224162D01*
X204221Y224287D01*
X204083Y224426D01*
X204069Y224439D01*
X204055Y224467D01*
X204013Y224509D01*
X203972Y224578D01*
X203916Y224661D01*
X203861Y224758D01*
X203791Y224869D01*
X203722Y225008D01*
X203653Y225161D01*
X203583Y225327D01*
X203528Y225507D01*
X203472Y225701D01*
X203431Y225909D01*
X203389Y226131D01*
X203375Y226367D01*
X203361Y226617D01*
Y226755D01*
X203375Y226852D01*
X203389Y226963D01*
X203403Y227102D01*
X203431Y227255D01*
X203458Y227407D01*
X203556Y227768D01*
X203694Y228128D01*
X203778Y228309D01*
X203875Y228489D01*
X203999Y228655D01*
X204138Y228808D01*
X204152Y228822D01*
X204166Y228850D01*
X204221Y228877D01*
X204277Y228933D01*
X204346Y229002D01*
X204443Y229071D01*
X204540Y229141D01*
X204665Y229224D01*
X204929Y229363D01*
X205261Y229501D01*
X205428Y229557D01*
X205622Y229585D01*
X205816Y229612D01*
X206024Y229626D01*
X206052D01*
X206121D01*
X206232Y229612D01*
X206385Y229598D01*
X206551Y229571D01*
X206745Y229515D01*
X206953Y229460D01*
X207161Y229377D01*
X207189Y229363D01*
X207258Y229335D01*
X207369Y229279D01*
X207522Y229196D01*
X207688Y229085D01*
X207896Y228947D01*
X208104Y228780D01*
X208340Y228586D01*
X208368Y228558D01*
X208451Y228489D01*
X208521Y228420D01*
X208590Y228350D01*
X208673Y228267D01*
X208784Y228156D01*
X208895Y228045D01*
X209020Y227906D01*
X209158Y227768D01*
X209311Y227601D01*
X209464Y227421D01*
X209644Y227227D01*
X209824Y227005D01*
X210018Y226783D01*
X210032Y226769D01*
X210060Y226742D01*
X210102Y226686D01*
X210157Y226617D01*
X210240Y226534D01*
X210323Y226436D01*
X210504Y226215D01*
X210712Y225979D01*
X210920Y225757D01*
X211100Y225563D01*
X211169Y225480D01*
X211239Y225410D01*
X211253Y225396D01*
X211294Y225355D01*
X211350Y225299D01*
X211433Y225230D01*
X211530Y225161D01*
X211627Y225077D01*
X211863Y224911D01*
Y229640D01*
X213000D01*
Y223274D01*
D02*
G37*
G36*
Y219031D02*
Y217699D01*
X203403Y213983D01*
Y215369D01*
X210379Y217866D01*
X210393D01*
X210420Y217880D01*
X210462Y217894D01*
X210518Y217921D01*
X210601Y217935D01*
X210684Y217963D01*
X210892Y218032D01*
X211128Y218115D01*
X211391Y218199D01*
X211946Y218365D01*
X211932D01*
X211904Y218379D01*
X211863Y218393D01*
X211807Y218407D01*
X211655Y218448D01*
X211447Y218518D01*
X211211Y218587D01*
X210947Y218670D01*
X210670Y218767D01*
X210379Y218878D01*
X203403Y221485D01*
Y222775D01*
X213000Y219031D01*
D02*
G37*
G36*
Y207797D02*
X205469Y202777D01*
X213000D01*
Y201556D01*
X203403D01*
Y202860D01*
X210947Y207894D01*
X203403D01*
Y209115D01*
X213000D01*
Y207797D01*
D02*
G37*
G36*
X208465Y199920D02*
X208645D01*
X208853Y199906D01*
X209061Y199878D01*
X209533Y199837D01*
X210032Y199767D01*
X210504Y199670D01*
X210739Y199601D01*
X210947Y199532D01*
X210961D01*
X210989Y199518D01*
X211045Y199490D01*
X211128Y199462D01*
X211211Y199421D01*
X211322Y199365D01*
X211558Y199227D01*
X211821Y199060D01*
X212099Y198866D01*
X212362Y198616D01*
X212598Y198339D01*
Y198325D01*
X212626Y198297D01*
X212653Y198256D01*
X212681Y198200D01*
X212723Y198117D01*
X212778Y198034D01*
X212834Y197923D01*
X212875Y197812D01*
X212986Y197549D01*
X213083Y197230D01*
X213139Y196883D01*
X213166Y196495D01*
Y196384D01*
X213153Y196314D01*
Y196217D01*
X213139Y196106D01*
X213083Y195843D01*
X213014Y195551D01*
X212903Y195246D01*
X212750Y194941D01*
X212653Y194789D01*
X212542Y194650D01*
X212528Y194636D01*
X212515Y194622D01*
X212473Y194581D01*
X212431Y194539D01*
X212362Y194484D01*
X212279Y194414D01*
X212085Y194276D01*
X211835Y194137D01*
X211530Y193998D01*
X211183Y193887D01*
X210781Y193804D01*
X210684Y194941D01*
X210698D01*
X210726Y194955D01*
X210753D01*
X210809Y194969D01*
X210961Y195011D01*
X211128Y195066D01*
X211322Y195135D01*
X211516Y195233D01*
X211696Y195343D01*
X211849Y195482D01*
X211863Y195496D01*
X211904Y195551D01*
X211960Y195649D01*
X212015Y195760D01*
X212085Y195912D01*
X212140Y196092D01*
X212182Y196300D01*
X212196Y196522D01*
Y196619D01*
X212182Y196716D01*
X212168Y196841D01*
X212140Y196994D01*
X212099Y197146D01*
X212043Y197313D01*
X211960Y197465D01*
X211946Y197479D01*
X211918Y197535D01*
X211863Y197618D01*
X211780Y197701D01*
X211682Y197812D01*
X211572Y197923D01*
X211447Y198034D01*
X211294Y198145D01*
X211280Y198159D01*
X211211Y198186D01*
X211114Y198242D01*
X210989Y198297D01*
X210823Y198367D01*
X210629Y198436D01*
X210407Y198505D01*
X210157Y198575D01*
X210143D01*
X210129Y198589D01*
X210088D01*
X210032Y198603D01*
X209893Y198630D01*
X209713Y198672D01*
X209491Y198700D01*
X209256Y198727D01*
X208992Y198741D01*
X208715Y198755D01*
X208701D01*
X208659D01*
X208590D01*
X208479D01*
X208507Y198741D01*
X208576Y198686D01*
X208673Y198603D01*
X208812Y198505D01*
X208950Y198367D01*
X209103Y198200D01*
X209256Y198006D01*
X209394Y197784D01*
X209408Y197757D01*
X209450Y197673D01*
X209505Y197549D01*
X209561Y197396D01*
X209630Y197188D01*
X209685Y196966D01*
X209727Y196716D01*
X209741Y196453D01*
Y196342D01*
X209727Y196259D01*
X209713Y196148D01*
X209699Y196037D01*
X209672Y195898D01*
X209630Y195760D01*
X209533Y195441D01*
X209464Y195274D01*
X209380Y195108D01*
X209283Y194927D01*
X209158Y194761D01*
X209034Y194595D01*
X208881Y194442D01*
X208867Y194428D01*
X208839Y194400D01*
X208798Y194373D01*
X208729Y194317D01*
X208631Y194248D01*
X208534Y194179D01*
X208410Y194109D01*
X208271Y194040D01*
X208118Y193957D01*
X207952Y193887D01*
X207758Y193818D01*
X207564Y193749D01*
X207342Y193693D01*
X207106Y193665D01*
X206870Y193638D01*
X206607Y193624D01*
X206593D01*
X206537D01*
X206468D01*
X206371Y193638D01*
X206246Y193652D01*
X206094Y193665D01*
X205941Y193693D01*
X205761Y193735D01*
X205400Y193832D01*
X205206Y193901D01*
X204998Y193984D01*
X204804Y194081D01*
X204624Y194206D01*
X204429Y194331D01*
X204263Y194484D01*
X204249Y194498D01*
X204221Y194525D01*
X204180Y194567D01*
X204124Y194636D01*
X204055Y194719D01*
X203972Y194830D01*
X203902Y194941D01*
X203805Y195080D01*
X203722Y195219D01*
X203653Y195385D01*
X203500Y195760D01*
X203445Y195954D01*
X203403Y196176D01*
X203375Y196397D01*
X203361Y196633D01*
Y196730D01*
X203375Y196800D01*
Y196869D01*
X203389Y196966D01*
X203431Y197202D01*
X203486Y197465D01*
X203583Y197757D01*
X203708Y198048D01*
X203875Y198339D01*
Y198353D01*
X203902Y198367D01*
X203930Y198408D01*
X203972Y198464D01*
X204083Y198603D01*
X204235Y198783D01*
X204443Y198963D01*
X204693Y199171D01*
X204984Y199351D01*
X205317Y199518D01*
X205331D01*
X205359Y199532D01*
X205414Y199559D01*
X205483Y199587D01*
X205580Y199615D01*
X205705Y199657D01*
X205844Y199684D01*
X205996Y199726D01*
X206177Y199767D01*
X206385Y199809D01*
X206607Y199837D01*
X206842Y199865D01*
X207106Y199892D01*
X207383Y199920D01*
X207688Y199934D01*
X208007D01*
X208021D01*
X208091D01*
X208188D01*
X208312D01*
X208465Y199920D01*
D02*
G37*
G36*
X213000Y190822D02*
X204970D01*
X213000Y188021D01*
Y186884D01*
X204832Y184110D01*
X213000D01*
Y182890D01*
X203403D01*
Y184790D01*
X210212Y187064D01*
X210226D01*
X210254Y187078D01*
X210296Y187092D01*
X210365Y187120D01*
X210531Y187175D01*
X210739Y187244D01*
X210975Y187314D01*
X211211Y187397D01*
X211433Y187466D01*
X211627Y187522D01*
X211599Y187536D01*
X211530Y187549D01*
X211405Y187591D01*
X211239Y187647D01*
X211017Y187716D01*
X210753Y187813D01*
X210448Y187910D01*
X210088Y188035D01*
X203403Y190337D01*
Y192043D01*
X213000D01*
Y190822D01*
D02*
G37*
G36*
X210115Y177842D02*
X208937D01*
Y181489D01*
X210115D01*
Y177842D01*
D02*
G37*
G36*
X208479Y176815D02*
X208604D01*
X208756Y176801D01*
X208923Y176774D01*
X209103Y176760D01*
X209505Y176691D01*
X209949Y176579D01*
X210393Y176427D01*
X210615Y176344D01*
X210837Y176233D01*
X210850D01*
X210892Y176205D01*
X210947Y176177D01*
X211031Y176122D01*
X211128Y176066D01*
X211225Y175997D01*
X211488Y175803D01*
X211766Y175567D01*
X212057Y175290D01*
X212334Y174957D01*
X212584Y174569D01*
Y174555D01*
X212612Y174527D01*
X212639Y174458D01*
X212681Y174375D01*
X212723Y174277D01*
X212764Y174166D01*
X212820Y174028D01*
X212875Y173875D01*
X212931Y173709D01*
X212986Y173528D01*
X213069Y173126D01*
X213139Y172696D01*
X213166Y172239D01*
Y172100D01*
X213153Y172017D01*
Y171892D01*
X213125Y171753D01*
X213111Y171601D01*
X213083Y171420D01*
X213000Y171046D01*
X212889Y170644D01*
X212723Y170228D01*
X212626Y170020D01*
X212515Y169812D01*
X212501Y169798D01*
X212487Y169770D01*
X212445Y169715D01*
X212390Y169632D01*
X212334Y169548D01*
X212251Y169451D01*
X212043Y169215D01*
X211793Y168952D01*
X211488Y168675D01*
X211142Y168425D01*
X210739Y168189D01*
X210726D01*
X210684Y168161D01*
X210629Y168134D01*
X210545Y168106D01*
X210434Y168064D01*
X210310Y168023D01*
X210171Y167967D01*
X210018Y167926D01*
X209838Y167870D01*
X209658Y167815D01*
X209242Y167731D01*
X208812Y167676D01*
X208340Y167648D01*
X208326D01*
X208312D01*
X208229D01*
X208104Y167662D01*
X207938D01*
X207744Y167690D01*
X207508Y167718D01*
X207245Y167759D01*
X206967Y167815D01*
X206676Y167870D01*
X206371Y167953D01*
X206066Y168064D01*
X205747Y168189D01*
X205442Y168328D01*
X205137Y168508D01*
X204859Y168702D01*
X204596Y168924D01*
X204582Y168938D01*
X204540Y168980D01*
X204471Y169063D01*
X204388Y169160D01*
X204277Y169285D01*
X204166Y169437D01*
X204041Y169618D01*
X203916Y169826D01*
X203791Y170047D01*
X203667Y170297D01*
X203556Y170574D01*
X203445Y170866D01*
X203361Y171185D01*
X203292Y171518D01*
X203251Y171864D01*
X203237Y172239D01*
Y172363D01*
X203251Y172461D01*
Y172585D01*
X203264Y172710D01*
X203292Y172877D01*
X203320Y173043D01*
X203389Y173404D01*
X203500Y173820D01*
X203667Y174222D01*
X203764Y174430D01*
X203875Y174638D01*
X203888Y174652D01*
X203902Y174680D01*
X203944Y174735D01*
X203986Y174818D01*
X204055Y174902D01*
X204138Y175012D01*
X204332Y175248D01*
X204582Y175498D01*
X204887Y175775D01*
X205248Y176039D01*
X205650Y176261D01*
X205664D01*
X205705Y176288D01*
X205761Y176316D01*
X205844Y176344D01*
X205955Y176399D01*
X206080Y176441D01*
X206232Y176496D01*
X206399Y176552D01*
X206579Y176593D01*
X206773Y176649D01*
X206995Y176704D01*
X207217Y176746D01*
X207702Y176801D01*
X208229Y176829D01*
X208243D01*
X208299D01*
X208368D01*
X208479Y176815D01*
D02*
G37*
G36*
X213000Y159105D02*
X203403D01*
Y166053D01*
X204540D01*
Y160381D01*
X207467D01*
Y165693D01*
X208604D01*
Y160381D01*
X211863D01*
Y166275D01*
X213000D01*
Y159105D01*
D02*
G37*
G36*
Y155638D02*
X205469Y150618D01*
X213000D01*
Y149397D01*
X203403D01*
Y150701D01*
X210947Y155735D01*
X203403D01*
Y156956D01*
X213000D01*
Y155638D01*
D02*
G37*
G36*
Y137568D02*
X212986D01*
X212931D01*
X212847D01*
X212736Y137582D01*
X212612Y137596D01*
X212473Y137623D01*
X212334Y137651D01*
X212182Y137706D01*
X212168D01*
X212154Y137720D01*
X212071Y137748D01*
X211946Y137803D01*
X211780Y137887D01*
X211585Y137998D01*
X211364Y138136D01*
X211142Y138289D01*
X210906Y138483D01*
X210892D01*
X210878Y138511D01*
X210795Y138580D01*
X210670Y138705D01*
X210490Y138885D01*
X210282Y139093D01*
X210032Y139357D01*
X209755Y139676D01*
X209464Y140022D01*
X209450Y140036D01*
X209408Y140092D01*
X209339Y140175D01*
X209256Y140272D01*
X209145Y140397D01*
X209020Y140549D01*
X208881Y140702D01*
X208729Y140882D01*
X208396Y141229D01*
X208063Y141576D01*
X207896Y141742D01*
X207730Y141895D01*
X207577Y142033D01*
X207425Y142144D01*
X207411D01*
X207397Y142172D01*
X207356Y142200D01*
X207300Y142227D01*
X207148Y142325D01*
X206967Y142436D01*
X206745Y142533D01*
X206510Y142630D01*
X206246Y142685D01*
X205996Y142713D01*
X205983D01*
X205969D01*
X205886Y142699D01*
X205747Y142685D01*
X205594Y142644D01*
X205400Y142588D01*
X205206Y142491D01*
X205012Y142366D01*
X204818Y142200D01*
X204790Y142172D01*
X204734Y142103D01*
X204665Y142006D01*
X204568Y141853D01*
X204485Y141659D01*
X204402Y141437D01*
X204346Y141173D01*
X204332Y140882D01*
Y140799D01*
X204346Y140744D01*
X204360Y140577D01*
X204402Y140383D01*
X204457Y140175D01*
X204554Y139939D01*
X204679Y139717D01*
X204845Y139509D01*
X204873Y139482D01*
X204942Y139426D01*
X205053Y139343D01*
X205220Y139260D01*
X205414Y139163D01*
X205664Y139079D01*
X205941Y139024D01*
X206260Y138996D01*
X206135Y137790D01*
X206121D01*
X206080Y137803D01*
X206010D01*
X205913Y137817D01*
X205802Y137845D01*
X205678Y137873D01*
X205525Y137914D01*
X205372Y137956D01*
X205040Y138067D01*
X204707Y138233D01*
X204540Y138330D01*
X204374Y138455D01*
X204221Y138580D01*
X204083Y138719D01*
X204069Y138733D01*
X204055Y138760D01*
X204013Y138802D01*
X203972Y138871D01*
X203916Y138955D01*
X203861Y139052D01*
X203791Y139163D01*
X203722Y139301D01*
X203653Y139454D01*
X203583Y139620D01*
X203528Y139801D01*
X203472Y139995D01*
X203431Y140203D01*
X203389Y140425D01*
X203375Y140660D01*
X203361Y140910D01*
Y141049D01*
X203375Y141146D01*
X203389Y141257D01*
X203403Y141395D01*
X203431Y141548D01*
X203458Y141700D01*
X203556Y142061D01*
X203694Y142422D01*
X203778Y142602D01*
X203875Y142782D01*
X203999Y142949D01*
X204138Y143101D01*
X204152Y143115D01*
X204166Y143143D01*
X204221Y143171D01*
X204277Y143226D01*
X204346Y143295D01*
X204443Y143365D01*
X204540Y143434D01*
X204665Y143517D01*
X204929Y143656D01*
X205261Y143795D01*
X205428Y143850D01*
X205622Y143878D01*
X205816Y143906D01*
X206024Y143919D01*
X206052D01*
X206121D01*
X206232Y143906D01*
X206385Y143892D01*
X206551Y143864D01*
X206745Y143808D01*
X206953Y143753D01*
X207161Y143670D01*
X207189Y143656D01*
X207258Y143628D01*
X207369Y143573D01*
X207522Y143490D01*
X207688Y143379D01*
X207896Y143240D01*
X208104Y143074D01*
X208340Y142879D01*
X208368Y142852D01*
X208451Y142782D01*
X208521Y142713D01*
X208590Y142644D01*
X208673Y142560D01*
X208784Y142449D01*
X208895Y142338D01*
X209020Y142200D01*
X209158Y142061D01*
X209311Y141895D01*
X209464Y141714D01*
X209644Y141520D01*
X209824Y141298D01*
X210018Y141076D01*
X210032Y141063D01*
X210060Y141035D01*
X210102Y140979D01*
X210157Y140910D01*
X210240Y140827D01*
X210323Y140730D01*
X210504Y140508D01*
X210712Y140272D01*
X210920Y140050D01*
X211100Y139856D01*
X211169Y139773D01*
X211239Y139704D01*
X211253Y139690D01*
X211294Y139648D01*
X211350Y139593D01*
X211433Y139523D01*
X211530Y139454D01*
X211627Y139371D01*
X211863Y139204D01*
Y143933D01*
X213000D01*
Y137568D01*
D02*
G37*
G36*
Y134933D02*
X204970D01*
X213000Y132131D01*
Y130994D01*
X204832Y128220D01*
X213000D01*
Y127000D01*
X203403D01*
Y128900D01*
X210212Y131174D01*
X210226D01*
X210254Y131188D01*
X210296Y131202D01*
X210365Y131230D01*
X210531Y131285D01*
X210739Y131355D01*
X210975Y131424D01*
X211211Y131507D01*
X211433Y131577D01*
X211627Y131632D01*
X211599Y131646D01*
X211530Y131660D01*
X211405Y131701D01*
X211239Y131757D01*
X211017Y131826D01*
X210753Y131923D01*
X210448Y132020D01*
X210088Y132145D01*
X203403Y134447D01*
Y136153D01*
X213000D01*
Y134933D01*
D02*
G37*
G36*
X85946Y111812D02*
X85989D01*
X86101Y111791D01*
X86235Y111769D01*
X86376Y111734D01*
X86530Y111685D01*
X86678Y111615D01*
X86685D01*
X86692Y111608D01*
X86713Y111594D01*
X86741Y111579D01*
X86812Y111537D01*
X86903Y111474D01*
X87002Y111396D01*
X87100Y111305D01*
X87199Y111192D01*
X87283Y111073D01*
Y111066D01*
X87290Y111059D01*
X87304Y111038D01*
X87311Y111010D01*
X87346Y110939D01*
X87382Y110848D01*
X87424Y110728D01*
X87452Y110594D01*
X87480Y110447D01*
X87487Y110285D01*
Y110250D01*
X87480Y110214D01*
Y110158D01*
X87473Y110095D01*
X87459Y110024D01*
X87438Y109940D01*
X87417Y109856D01*
X87389Y109757D01*
X87353Y109659D01*
X87311Y109560D01*
X87255Y109455D01*
X87192Y109356D01*
X87121Y109258D01*
X87037Y109159D01*
X86938Y109068D01*
X86931Y109061D01*
X86910Y109046D01*
X86882Y109025D01*
X86833Y108997D01*
X86770Y108955D01*
X86699Y108920D01*
X86608Y108878D01*
X86509Y108835D01*
X86390Y108786D01*
X86256Y108744D01*
X86108Y108709D01*
X85946Y108674D01*
X85763Y108638D01*
X85566Y108617D01*
X85355Y108603D01*
X85130Y108596D01*
X85123D01*
X85116D01*
X85095D01*
X85067D01*
X84997Y108603D01*
X84898D01*
X84785Y108610D01*
X84652Y108624D01*
X84504Y108638D01*
X84342Y108659D01*
X84180Y108688D01*
X84004Y108723D01*
X83836Y108765D01*
X83667Y108814D01*
X83505Y108878D01*
X83350Y108948D01*
X83202Y109025D01*
X83076Y109117D01*
X83069Y109124D01*
X83055Y109138D01*
X83027Y109166D01*
X82984Y109201D01*
X82942Y109243D01*
X82900Y109300D01*
X82844Y109370D01*
X82794Y109440D01*
X82745Y109525D01*
X82689Y109616D01*
X82647Y109722D01*
X82597Y109827D01*
X82562Y109947D01*
X82534Y110074D01*
X82520Y110207D01*
X82513Y110348D01*
Y110404D01*
X82520Y110447D01*
Y110496D01*
X82527Y110552D01*
X82555Y110686D01*
X82590Y110834D01*
X82647Y110988D01*
X82731Y111143D01*
X82780Y111221D01*
X82837Y111291D01*
X82844Y111298D01*
X82851Y111305D01*
X82872Y111326D01*
X82893Y111347D01*
X82928Y111382D01*
X82970Y111411D01*
X83069Y111488D01*
X83195Y111565D01*
X83350Y111636D01*
X83526Y111699D01*
X83723Y111741D01*
X83772Y111143D01*
X83765D01*
X83758Y111136D01*
X83716Y111129D01*
X83653Y111108D01*
X83575Y111080D01*
X83491Y111052D01*
X83406Y111010D01*
X83329Y110960D01*
X83266Y110911D01*
X83252Y110897D01*
X83223Y110869D01*
X83181Y110820D01*
X83132Y110749D01*
X83090Y110658D01*
X83048Y110559D01*
X83019Y110440D01*
X83005Y110313D01*
Y110264D01*
X83012Y110207D01*
X83027Y110144D01*
X83048Y110060D01*
X83076Y109975D01*
X83111Y109891D01*
X83167Y109806D01*
X83174Y109792D01*
X83202Y109757D01*
X83252Y109708D01*
X83322Y109644D01*
X83406Y109574D01*
X83505Y109497D01*
X83631Y109426D01*
X83772Y109356D01*
X83779D01*
X83793Y109349D01*
X83814Y109342D01*
X83843Y109328D01*
X83885Y109321D01*
X83934Y109307D01*
X83990Y109293D01*
X84061Y109279D01*
X84138Y109258D01*
X84222Y109243D01*
X84314Y109229D01*
X84412Y109222D01*
X84525Y109208D01*
X84638Y109201D01*
X84764Y109194D01*
X84891D01*
X84884Y109201D01*
X84842Y109229D01*
X84785Y109279D01*
X84715Y109342D01*
X84631Y109412D01*
X84553Y109504D01*
X84476Y109602D01*
X84405Y109715D01*
Y109722D01*
X84398Y109729D01*
X84377Y109771D01*
X84356Y109834D01*
X84321Y109919D01*
X84293Y110017D01*
X84272Y110130D01*
X84251Y110250D01*
X84244Y110376D01*
Y110433D01*
X84251Y110475D01*
X84258Y110531D01*
X84265Y110587D01*
X84279Y110658D01*
X84300Y110728D01*
X84349Y110890D01*
X84384Y110974D01*
X84434Y111059D01*
X84483Y111143D01*
X84539Y111235D01*
X84609Y111319D01*
X84687Y111396D01*
X84694Y111404D01*
X84708Y111418D01*
X84729Y111439D01*
X84764Y111460D01*
X84813Y111495D01*
X84863Y111530D01*
X84926Y111565D01*
X84997Y111608D01*
X85074Y111650D01*
X85158Y111685D01*
X85257Y111720D01*
X85355Y111755D01*
X85461Y111776D01*
X85580Y111798D01*
X85700Y111812D01*
X85827Y111819D01*
X85834D01*
X85848D01*
X85869D01*
X85904D01*
X85946Y111812D01*
D02*
G37*
G36*
X87403Y106493D02*
X83596D01*
X83603Y106486D01*
X83631Y106450D01*
X83674Y106408D01*
X83723Y106338D01*
X83786Y106260D01*
X83857Y106162D01*
X83934Y106049D01*
X84011Y105923D01*
Y105916D01*
X84018Y105908D01*
X84047Y105866D01*
X84082Y105796D01*
X84124Y105711D01*
X84173Y105613D01*
X84222Y105507D01*
X84272Y105402D01*
X84314Y105296D01*
X83737D01*
Y105303D01*
X83723Y105317D01*
X83716Y105346D01*
X83695Y105381D01*
X83674Y105423D01*
X83646Y105472D01*
X83575Y105592D01*
X83498Y105733D01*
X83399Y105873D01*
X83287Y106021D01*
X83167Y106169D01*
X83160Y106176D01*
X83153Y106183D01*
X83132Y106204D01*
X83111Y106232D01*
X83041Y106295D01*
X82956Y106380D01*
X82858Y106464D01*
X82745Y106556D01*
X82632Y106633D01*
X82513Y106704D01*
Y107091D01*
X87403D01*
Y106493D01*
D02*
G37*
G36*
Y103657D02*
X86390Y103017D01*
X86383D01*
X86369Y103003D01*
X86347Y102989D01*
X86319Y102968D01*
X86242Y102918D01*
X86143Y102855D01*
X86038Y102778D01*
X85925Y102700D01*
X85820Y102623D01*
X85721Y102552D01*
X85714Y102545D01*
X85686Y102524D01*
X85644Y102489D01*
X85595Y102440D01*
X85489Y102334D01*
X85440Y102278D01*
X85398Y102222D01*
X85391Y102215D01*
X85383Y102201D01*
X85369Y102172D01*
X85348Y102130D01*
X85327Y102088D01*
X85306Y102039D01*
X85271Y101926D01*
Y101919D01*
X85264Y101905D01*
Y101877D01*
X85257Y101842D01*
X85250Y101793D01*
Y101736D01*
X85243Y101659D01*
Y100829D01*
X87403D01*
Y100181D01*
X82534D01*
Y102440D01*
X82541Y102496D01*
Y102559D01*
X82548Y102707D01*
X82569Y102862D01*
X82590Y103031D01*
X82625Y103186D01*
X82647Y103263D01*
X82668Y103326D01*
Y103333D01*
X82675Y103341D01*
X82696Y103383D01*
X82724Y103446D01*
X82773Y103523D01*
X82837Y103608D01*
X82921Y103699D01*
X83019Y103784D01*
X83132Y103868D01*
X83139D01*
X83146Y103875D01*
X83188Y103903D01*
X83259Y103932D01*
X83350Y103974D01*
X83456Y104009D01*
X83582Y104044D01*
X83716Y104065D01*
X83864Y104072D01*
X83871D01*
X83885D01*
X83913D01*
X83948Y104065D01*
X83997D01*
X84047Y104058D01*
X84166Y104030D01*
X84307Y103988D01*
X84455Y103932D01*
X84602Y103847D01*
X84673Y103791D01*
X84743Y103735D01*
X84750Y103727D01*
X84757Y103720D01*
X84778Y103699D01*
X84799Y103671D01*
X84828Y103636D01*
X84856Y103594D01*
X84891Y103538D01*
X84933Y103481D01*
X84968Y103411D01*
X85003Y103333D01*
X85046Y103249D01*
X85081Y103158D01*
X85109Y103052D01*
X85144Y102947D01*
X85165Y102827D01*
X85186Y102700D01*
X85194Y102714D01*
X85208Y102742D01*
X85236Y102785D01*
X85264Y102841D01*
X85341Y102968D01*
X85391Y103031D01*
X85433Y103087D01*
X85447Y103101D01*
X85482Y103136D01*
X85538Y103193D01*
X85609Y103263D01*
X85707Y103341D01*
X85813Y103432D01*
X85939Y103523D01*
X86080Y103622D01*
X87403Y104459D01*
Y103657D01*
D02*
G37*
G36*
X103445Y121749D02*
X99639D01*
X99646Y121742D01*
X99674Y121707D01*
X99716Y121665D01*
X99765Y121594D01*
X99829Y121517D01*
X99899Y121419D01*
X99976Y121306D01*
X100054Y121179D01*
Y121172D01*
X100061Y121165D01*
X100089Y121123D01*
X100124Y121053D01*
X100166Y120968D01*
X100216Y120870D01*
X100265Y120764D01*
X100314Y120659D01*
X100356Y120553D01*
X99779D01*
Y120560D01*
X99765Y120574D01*
X99758Y120602D01*
X99737Y120638D01*
X99716Y120680D01*
X99688Y120729D01*
X99617Y120849D01*
X99540Y120989D01*
X99441Y121130D01*
X99329Y121278D01*
X99209Y121426D01*
X99202Y121433D01*
X99195Y121440D01*
X99174Y121461D01*
X99153Y121489D01*
X99083Y121552D01*
X98998Y121637D01*
X98900Y121721D01*
X98787Y121812D01*
X98675Y121890D01*
X98555Y121960D01*
Y122347D01*
X103445D01*
Y121749D01*
D02*
G37*
G36*
Y117964D02*
X99639D01*
X99646Y117957D01*
X99674Y117922D01*
X99716Y117879D01*
X99765Y117809D01*
X99829Y117732D01*
X99899Y117633D01*
X99976Y117521D01*
X100054Y117394D01*
Y117387D01*
X100061Y117380D01*
X100089Y117338D01*
X100124Y117267D01*
X100166Y117183D01*
X100216Y117084D01*
X100265Y116979D01*
X100314Y116873D01*
X100356Y116768D01*
X99779D01*
Y116775D01*
X99765Y116789D01*
X99758Y116817D01*
X99737Y116852D01*
X99716Y116895D01*
X99688Y116944D01*
X99617Y117063D01*
X99540Y117204D01*
X99441Y117345D01*
X99329Y117493D01*
X99209Y117640D01*
X99202Y117647D01*
X99195Y117654D01*
X99174Y117676D01*
X99153Y117704D01*
X99083Y117767D01*
X98998Y117851D01*
X98900Y117936D01*
X98787Y118027D01*
X98675Y118105D01*
X98555Y118175D01*
Y118562D01*
X103445D01*
Y117964D01*
D02*
G37*
G36*
Y115128D02*
X102432Y114488D01*
X102425D01*
X102411Y114474D01*
X102389Y114460D01*
X102361Y114439D01*
X102284Y114390D01*
X102185Y114326D01*
X102080Y114249D01*
X101967Y114172D01*
X101862Y114094D01*
X101763Y114024D01*
X101756Y114017D01*
X101728Y113996D01*
X101686Y113961D01*
X101637Y113911D01*
X101531Y113806D01*
X101482Y113750D01*
X101440Y113693D01*
X101433Y113686D01*
X101426Y113672D01*
X101412Y113644D01*
X101390Y113602D01*
X101369Y113560D01*
X101348Y113510D01*
X101313Y113398D01*
Y113391D01*
X101306Y113377D01*
Y113348D01*
X101299Y113313D01*
X101292Y113264D01*
Y113208D01*
X101285Y113130D01*
Y112300D01*
X103445D01*
Y111653D01*
X98576D01*
Y113911D01*
X98583Y113968D01*
Y114031D01*
X98590Y114179D01*
X98611Y114333D01*
X98632Y114502D01*
X98668Y114657D01*
X98689Y114734D01*
X98710Y114798D01*
Y114805D01*
X98717Y114812D01*
X98738Y114854D01*
X98766Y114917D01*
X98815Y114995D01*
X98879Y115079D01*
X98963Y115171D01*
X99062Y115255D01*
X99174Y115340D01*
X99181D01*
X99188Y115347D01*
X99230Y115375D01*
X99301Y115403D01*
X99392Y115445D01*
X99498Y115480D01*
X99625Y115515D01*
X99758Y115537D01*
X99906Y115544D01*
X99913D01*
X99927D01*
X99955D01*
X99990Y115537D01*
X100040D01*
X100089Y115529D01*
X100208Y115501D01*
X100349Y115459D01*
X100497Y115403D01*
X100645Y115318D01*
X100715Y115262D01*
X100785Y115206D01*
X100792Y115199D01*
X100799Y115192D01*
X100821Y115171D01*
X100842Y115143D01*
X100870Y115107D01*
X100898Y115065D01*
X100933Y115009D01*
X100975Y114953D01*
X101011Y114882D01*
X101046Y114805D01*
X101088Y114720D01*
X101123Y114629D01*
X101151Y114523D01*
X101186Y114418D01*
X101208Y114298D01*
X101229Y114172D01*
X101236Y114186D01*
X101250Y114214D01*
X101278Y114256D01*
X101306Y114312D01*
X101383Y114439D01*
X101433Y114502D01*
X101475Y114559D01*
X101489Y114573D01*
X101524Y114608D01*
X101580Y114664D01*
X101651Y114734D01*
X101749Y114812D01*
X101855Y114903D01*
X101981Y114995D01*
X102122Y115093D01*
X103445Y115931D01*
Y115128D01*
D02*
G37*
G36*
X111085Y148005D02*
X111161D01*
X111249Y147999D01*
X111337Y147987D01*
X111537Y147970D01*
X111748Y147940D01*
X111948Y147899D01*
X112047Y147870D01*
X112135Y147841D01*
X112141D01*
X112153Y147835D01*
X112176Y147823D01*
X112212Y147811D01*
X112247Y147794D01*
X112294Y147770D01*
X112394Y147711D01*
X112505Y147641D01*
X112622Y147559D01*
X112734Y147453D01*
X112834Y147336D01*
Y147330D01*
X112845Y147318D01*
X112857Y147301D01*
X112869Y147277D01*
X112886Y147242D01*
X112910Y147207D01*
X112933Y147160D01*
X112951Y147113D01*
X112998Y147002D01*
X113039Y146867D01*
X113062Y146720D01*
X113074Y146556D01*
Y146509D01*
X113068Y146479D01*
Y146438D01*
X113062Y146391D01*
X113039Y146280D01*
X113010Y146157D01*
X112963Y146028D01*
X112898Y145899D01*
X112857Y145834D01*
X112810Y145775D01*
X112804Y145769D01*
X112798Y145764D01*
X112781Y145746D01*
X112763Y145728D01*
X112734Y145705D01*
X112699Y145675D01*
X112617Y145617D01*
X112511Y145558D01*
X112382Y145499D01*
X112235Y145453D01*
X112065Y145417D01*
X112024Y145899D01*
X112030D01*
X112042Y145904D01*
X112053D01*
X112077Y145910D01*
X112141Y145928D01*
X112212Y145951D01*
X112294Y145981D01*
X112376Y146022D01*
X112452Y146069D01*
X112517Y146127D01*
X112523Y146133D01*
X112540Y146157D01*
X112564Y146198D01*
X112587Y146245D01*
X112617Y146309D01*
X112640Y146385D01*
X112657Y146474D01*
X112663Y146567D01*
Y146608D01*
X112657Y146650D01*
X112652Y146702D01*
X112640Y146767D01*
X112622Y146831D01*
X112599Y146902D01*
X112564Y146966D01*
X112558Y146972D01*
X112546Y146996D01*
X112523Y147031D01*
X112487Y147066D01*
X112446Y147113D01*
X112399Y147160D01*
X112347Y147207D01*
X112282Y147254D01*
X112276Y147260D01*
X112247Y147271D01*
X112206Y147295D01*
X112153Y147318D01*
X112083Y147348D01*
X112000Y147377D01*
X111906Y147406D01*
X111801Y147436D01*
X111795D01*
X111789Y147442D01*
X111772D01*
X111748Y147448D01*
X111689Y147459D01*
X111613Y147477D01*
X111519Y147489D01*
X111419Y147500D01*
X111308Y147506D01*
X111191Y147512D01*
X111185D01*
X111167D01*
X111138D01*
X111091D01*
X111103Y147506D01*
X111132Y147483D01*
X111173Y147448D01*
X111232Y147406D01*
X111290Y147348D01*
X111355Y147277D01*
X111419Y147195D01*
X111478Y147101D01*
X111484Y147090D01*
X111502Y147054D01*
X111525Y147002D01*
X111549Y146937D01*
X111578Y146849D01*
X111601Y146755D01*
X111619Y146650D01*
X111625Y146538D01*
Y146491D01*
X111619Y146456D01*
X111613Y146409D01*
X111607Y146362D01*
X111595Y146303D01*
X111578Y146245D01*
X111537Y146110D01*
X111508Y146039D01*
X111472Y145969D01*
X111431Y145893D01*
X111378Y145822D01*
X111326Y145752D01*
X111261Y145687D01*
X111255Y145681D01*
X111243Y145670D01*
X111226Y145658D01*
X111197Y145634D01*
X111156Y145605D01*
X111114Y145576D01*
X111062Y145546D01*
X111003Y145517D01*
X110938Y145482D01*
X110868Y145453D01*
X110786Y145423D01*
X110704Y145394D01*
X110610Y145370D01*
X110510Y145359D01*
X110410Y145347D01*
X110299Y145341D01*
X110293D01*
X110269D01*
X110240D01*
X110199Y145347D01*
X110146Y145353D01*
X110082Y145359D01*
X110017Y145370D01*
X109941Y145388D01*
X109788Y145429D01*
X109706Y145458D01*
X109618Y145494D01*
X109536Y145535D01*
X109460Y145588D01*
X109378Y145640D01*
X109307Y145705D01*
X109301Y145711D01*
X109290Y145723D01*
X109272Y145740D01*
X109249Y145769D01*
X109219Y145805D01*
X109184Y145851D01*
X109155Y145899D01*
X109114Y145957D01*
X109078Y146016D01*
X109049Y146086D01*
X108984Y146245D01*
X108961Y146327D01*
X108944Y146421D01*
X108932Y146515D01*
X108926Y146614D01*
Y146655D01*
X108932Y146685D01*
Y146714D01*
X108938Y146755D01*
X108955Y146855D01*
X108979Y146966D01*
X109020Y147090D01*
X109073Y147213D01*
X109143Y147336D01*
Y147342D01*
X109155Y147348D01*
X109166Y147365D01*
X109184Y147389D01*
X109231Y147448D01*
X109296Y147524D01*
X109383Y147600D01*
X109489Y147688D01*
X109612Y147764D01*
X109753Y147835D01*
X109759D01*
X109771Y147841D01*
X109794Y147852D01*
X109824Y147864D01*
X109865Y147876D01*
X109917Y147893D01*
X109976Y147905D01*
X110041Y147923D01*
X110117Y147940D01*
X110205Y147958D01*
X110299Y147970D01*
X110399Y147981D01*
X110510Y147993D01*
X110627Y148005D01*
X110757Y148011D01*
X110891D01*
X110897D01*
X110927D01*
X110968D01*
X111020D01*
X111085Y148005D01*
D02*
G37*
G36*
X110211Y144854D02*
X110252Y144848D01*
X110305Y144842D01*
X110363Y144831D01*
X110428Y144819D01*
X110563Y144778D01*
X110633Y144754D01*
X110710Y144719D01*
X110786Y144678D01*
X110856Y144637D01*
X110927Y144584D01*
X110997Y144525D01*
X111003Y144520D01*
X111015Y144508D01*
X111032Y144490D01*
X111050Y144461D01*
X111079Y144426D01*
X111109Y144379D01*
X111144Y144320D01*
X111173Y144256D01*
X111208Y144179D01*
X111243Y144091D01*
X111273Y143997D01*
X111296Y143886D01*
X111320Y143769D01*
X111337Y143639D01*
X111349Y143493D01*
X111355Y143340D01*
Y142302D01*
X113004D01*
Y141762D01*
X108944D01*
Y143428D01*
X108949Y143516D01*
X108955Y143616D01*
X108961Y143722D01*
X108973Y143821D01*
X108984Y143909D01*
Y143921D01*
X108996Y143962D01*
X109008Y144015D01*
X109026Y144086D01*
X109055Y144162D01*
X109090Y144244D01*
X109131Y144332D01*
X109178Y144408D01*
X109184Y144420D01*
X109202Y144443D01*
X109237Y144479D01*
X109278Y144525D01*
X109331Y144578D01*
X109401Y144631D01*
X109477Y144690D01*
X109565Y144737D01*
X109577Y144743D01*
X109607Y144754D01*
X109659Y144778D01*
X109730Y144801D01*
X109812Y144819D01*
X109906Y144842D01*
X110011Y144854D01*
X110123Y144860D01*
X110129D01*
X110146D01*
X110170D01*
X110211Y144854D01*
D02*
G37*
G36*
X109425Y139867D02*
X113004D01*
Y139327D01*
X109425D01*
Y137989D01*
X108944D01*
Y141205D01*
X109425D01*
Y139867D01*
D02*
G37*
G36*
X97936Y149005D02*
X97977Y148999D01*
X98030Y148993D01*
X98088Y148981D01*
X98153Y148964D01*
X98288Y148923D01*
X98364Y148893D01*
X98435Y148852D01*
X98511Y148811D01*
X98581Y148764D01*
X98652Y148706D01*
X98722Y148641D01*
X98728Y148635D01*
X98740Y148624D01*
X98757Y148606D01*
X98775Y148577D01*
X98804Y148535D01*
X98834Y148494D01*
X98863Y148442D01*
X98898Y148383D01*
X98933Y148318D01*
X98963Y148242D01*
X98992Y148160D01*
X99021Y148078D01*
X99039Y147984D01*
X99057Y147884D01*
X99068Y147785D01*
X99074Y147673D01*
Y147614D01*
X99068Y147573D01*
X99062Y147520D01*
X99057Y147462D01*
X99045Y147397D01*
X99027Y147327D01*
X98986Y147168D01*
X98957Y147086D01*
X98927Y147010D01*
X98886Y146928D01*
X98839Y146846D01*
X98787Y146769D01*
X98722Y146699D01*
X98716Y146693D01*
X98705Y146681D01*
X98687Y146664D01*
X98658Y146640D01*
X98622Y146617D01*
X98581Y146582D01*
X98534Y146552D01*
X98476Y146517D01*
X98417Y146482D01*
X98347Y146453D01*
X98200Y146394D01*
X98112Y146370D01*
X98024Y146353D01*
X97930Y146341D01*
X97836Y146335D01*
X97830D01*
X97818D01*
X97795D01*
X97772Y146341D01*
X97736D01*
X97695Y146347D01*
X97601Y146359D01*
X97496Y146382D01*
X97390Y146417D01*
X97279Y146470D01*
X97173Y146535D01*
X97167D01*
X97161Y146546D01*
X97132Y146570D01*
X97085Y146617D01*
X97026Y146681D01*
X96968Y146763D01*
X96903Y146863D01*
X96850Y146975D01*
X96809Y147110D01*
Y147104D01*
X96803Y147098D01*
X96798Y147080D01*
X96786Y147057D01*
X96762Y147004D01*
X96727Y146934D01*
X96680Y146857D01*
X96622Y146781D01*
X96557Y146711D01*
X96487Y146646D01*
X96475Y146640D01*
X96451Y146623D01*
X96404Y146599D01*
X96346Y146576D01*
X96270Y146546D01*
X96181Y146523D01*
X96082Y146505D01*
X95976Y146500D01*
X95970D01*
X95958D01*
X95935D01*
X95900Y146505D01*
X95865Y146511D01*
X95818Y146517D01*
X95718Y146541D01*
X95601Y146576D01*
X95477Y146635D01*
X95413Y146670D01*
X95348Y146711D01*
X95290Y146763D01*
X95231Y146816D01*
X95225Y146822D01*
X95219Y146834D01*
X95202Y146852D01*
X95184Y146875D01*
X95161Y146904D01*
X95137Y146945D01*
X95108Y146992D01*
X95078Y147039D01*
X95049Y147098D01*
X95020Y147163D01*
X94996Y147233D01*
X94973Y147309D01*
X94938Y147473D01*
X94932Y147567D01*
X94926Y147661D01*
Y147714D01*
X94932Y147749D01*
X94938Y147796D01*
X94944Y147849D01*
X94949Y147908D01*
X94967Y147966D01*
X95002Y148107D01*
X95055Y148248D01*
X95090Y148318D01*
X95131Y148389D01*
X95184Y148453D01*
X95237Y148518D01*
X95243Y148524D01*
X95249Y148530D01*
X95266Y148547D01*
X95290Y148571D01*
X95325Y148594D01*
X95360Y148624D01*
X95448Y148682D01*
X95560Y148741D01*
X95689Y148794D01*
X95835Y148835D01*
X95912Y148841D01*
X95994Y148847D01*
X96000D01*
X96005D01*
X96041D01*
X96094Y148841D01*
X96158Y148829D01*
X96240Y148811D01*
X96322Y148782D01*
X96404Y148747D01*
X96487Y148694D01*
X96498Y148688D01*
X96522Y148665D01*
X96557Y148629D01*
X96604Y148582D01*
X96657Y148518D01*
X96710Y148442D01*
X96762Y148354D01*
X96809Y148248D01*
Y148254D01*
X96815Y148266D01*
X96821Y148283D01*
X96833Y148307D01*
X96862Y148377D01*
X96903Y148459D01*
X96962Y148547D01*
X97026Y148641D01*
X97108Y148729D01*
X97202Y148811D01*
X97208D01*
X97214Y148817D01*
X97249Y148841D01*
X97308Y148876D01*
X97384Y148911D01*
X97478Y148946D01*
X97590Y148981D01*
X97713Y149005D01*
X97848Y149011D01*
X97854D01*
X97871D01*
X97901D01*
X97936Y149005D01*
D02*
G37*
G36*
X96211Y145854D02*
X96252Y145848D01*
X96305Y145842D01*
X96363Y145831D01*
X96428Y145819D01*
X96563Y145778D01*
X96633Y145754D01*
X96710Y145719D01*
X96786Y145678D01*
X96856Y145637D01*
X96927Y145584D01*
X96997Y145526D01*
X97003Y145520D01*
X97015Y145508D01*
X97032Y145490D01*
X97050Y145461D01*
X97079Y145426D01*
X97108Y145379D01*
X97144Y145320D01*
X97173Y145256D01*
X97208Y145179D01*
X97243Y145091D01*
X97273Y144997D01*
X97296Y144886D01*
X97320Y144769D01*
X97337Y144640D01*
X97349Y144493D01*
X97355Y144340D01*
Y143302D01*
X99004D01*
Y142762D01*
X94944D01*
Y144428D01*
X94949Y144516D01*
X94955Y144616D01*
X94961Y144722D01*
X94973Y144821D01*
X94985Y144909D01*
Y144921D01*
X94996Y144962D01*
X95008Y145015D01*
X95026Y145085D01*
X95055Y145162D01*
X95090Y145244D01*
X95131Y145332D01*
X95178Y145408D01*
X95184Y145420D01*
X95202Y145443D01*
X95237Y145479D01*
X95278Y145526D01*
X95331Y145578D01*
X95401Y145631D01*
X95477Y145690D01*
X95565Y145737D01*
X95577Y145743D01*
X95606Y145754D01*
X95659Y145778D01*
X95730Y145801D01*
X95812Y145819D01*
X95906Y145842D01*
X96011Y145854D01*
X96123Y145860D01*
X96129D01*
X96146D01*
X96170D01*
X96211Y145854D01*
D02*
G37*
G36*
X95425Y140867D02*
X99004D01*
Y140327D01*
X95425D01*
Y138989D01*
X94944D01*
Y142205D01*
X95425D01*
Y140867D01*
D02*
G37*
%LPC*%
G36*
X14728Y137549D02*
X12547D01*
X14728Y136015D01*
Y137549D01*
D02*
G37*
G36*
X12913Y130421D02*
X12906D01*
X12899D01*
X12857Y130414D01*
X12793Y130407D01*
X12709Y130393D01*
X12624Y130358D01*
X12526Y130316D01*
X12435Y130253D01*
X12343Y130168D01*
X12336Y130154D01*
X12308Y130119D01*
X12273Y130063D01*
X12230Y129971D01*
X12188Y129866D01*
X12153Y129725D01*
X12125Y129563D01*
X12118Y129373D01*
Y127839D01*
X13729D01*
Y129289D01*
X13722Y129373D01*
X13715Y129472D01*
X13708Y129584D01*
X13694Y129697D01*
X13673Y129809D01*
X13645Y129908D01*
X13638Y129922D01*
X13624Y129950D01*
X13602Y129992D01*
X13574Y130049D01*
X13532Y130112D01*
X13483Y130175D01*
X13420Y130238D01*
X13349Y130288D01*
X13342Y130295D01*
X13314Y130309D01*
X13272Y130330D01*
X13216Y130358D01*
X13152Y130379D01*
X13082Y130400D01*
X12997Y130414D01*
X12913Y130421D01*
D02*
G37*
G36*
X20871Y130393D02*
X20864D01*
X20857D01*
X20814Y130386D01*
X20751Y130379D01*
X20667Y130365D01*
X20582Y130330D01*
X20484Y130288D01*
X20392Y130224D01*
X20301Y130140D01*
X20294Y130126D01*
X20266Y130091D01*
X20231Y130034D01*
X20188Y129943D01*
X20146Y129837D01*
X20111Y129697D01*
X20083Y129535D01*
X20076Y129345D01*
Y127811D01*
X21687D01*
Y129261D01*
X21680Y129345D01*
X21673Y129443D01*
X21666Y129556D01*
X21652Y129669D01*
X21631Y129781D01*
X21602Y129880D01*
X21595Y129894D01*
X21581Y129922D01*
X21560Y129964D01*
X21532Y130020D01*
X21490Y130084D01*
X21441Y130147D01*
X21377Y130210D01*
X21307Y130260D01*
X21300Y130267D01*
X21272Y130281D01*
X21230Y130302D01*
X21173Y130330D01*
X21110Y130351D01*
X21040Y130372D01*
X20955Y130386D01*
X20871Y130393D01*
D02*
G37*
G36*
X32430Y159229D02*
X32289D01*
X32190Y159215D01*
X32063Y159201D01*
X31922Y159173D01*
X31767Y159144D01*
X31598Y159102D01*
X31401Y159046D01*
X31217Y158989D01*
X31020Y158905D01*
X30809Y158806D01*
X30611Y158693D01*
X30414Y158552D01*
X30217Y158412D01*
X30033Y158228D01*
X30019Y158214D01*
X29991Y158186D01*
X29949Y158130D01*
X29892Y158045D01*
X29808Y157946D01*
X29737Y157819D01*
X29653Y157664D01*
X29568Y157495D01*
X29469Y157298D01*
X29385Y157072D01*
X29314Y156833D01*
X29244Y156565D01*
X29173Y156283D01*
X29131Y155973D01*
X29103Y155634D01*
X29089Y155282D01*
Y155254D01*
Y155197D01*
Y155099D01*
X29103Y154972D01*
X29117Y154817D01*
X29145Y154634D01*
X29173Y154422D01*
X29202Y154211D01*
X29314Y153731D01*
X29385Y153492D01*
X29483Y153252D01*
X29582Y153012D01*
X29709Y152787D01*
X29850Y152561D01*
X30019Y152364D01*
X30033Y152350D01*
X30062Y152322D01*
X30118Y152265D01*
X30188Y152209D01*
X30287Y152124D01*
X30400Y152040D01*
X30527Y151955D01*
X30682Y151856D01*
X30837Y151758D01*
X31020Y151673D01*
X31217Y151588D01*
X31429Y151504D01*
X31669Y151448D01*
X31908Y151391D01*
X32162Y151363D01*
X32430Y151349D01*
X32557D01*
X32683Y151363D01*
X32853Y151377D01*
X33064Y151405D01*
X33276Y151462D01*
X33515Y151518D01*
X33741Y151603D01*
X33713Y151617D01*
X33642Y151673D01*
X33515Y151744D01*
X33360Y151828D01*
X33163Y151913D01*
X32951Y152011D01*
X32712Y152096D01*
X32458Y152167D01*
X32782Y153097D01*
X32796D01*
X32839Y153083D01*
X32895Y153069D01*
X32965Y153041D01*
X33064Y153012D01*
X33177Y152970D01*
X33431Y152871D01*
X33727Y152730D01*
X34037Y152575D01*
X34333Y152392D01*
X34629Y152167D01*
X34643Y152181D01*
X34685Y152209D01*
X34742Y152279D01*
X34812Y152364D01*
X34897Y152477D01*
X34995Y152604D01*
X35094Y152759D01*
X35207Y152942D01*
X35306Y153153D01*
X35404Y153393D01*
X35503Y153647D01*
X35587Y153914D01*
X35672Y154225D01*
X35728Y154549D01*
X35757Y154901D01*
X35771Y155282D01*
Y155296D01*
Y155338D01*
Y155395D01*
Y155479D01*
X35757Y155592D01*
Y155705D01*
X35742Y155846D01*
X35714Y155987D01*
X35672Y156311D01*
X35602Y156663D01*
X35503Y157016D01*
X35362Y157354D01*
Y157368D01*
X35348Y157396D01*
X35320Y157439D01*
X35291Y157495D01*
X35193Y157664D01*
X35066Y157862D01*
X34897Y158087D01*
X34685Y158313D01*
X34446Y158538D01*
X34178Y158736D01*
X34164D01*
X34150Y158764D01*
X34107Y158778D01*
X34037Y158820D01*
X33966Y158848D01*
X33882Y158891D01*
X33670Y158989D01*
X33417Y159074D01*
X33121Y159159D01*
X32782Y159215D01*
X32430Y159229D01*
D02*
G37*
G36*
X206551Y198630D02*
X206537D01*
X206510D01*
X206454D01*
X206385Y198616D01*
X206288D01*
X206191Y198603D01*
X205969Y198561D01*
X205705Y198505D01*
X205428Y198408D01*
X205164Y198270D01*
X204929Y198089D01*
X204915D01*
X204901Y198062D01*
X204832Y197992D01*
X204734Y197881D01*
X204624Y197729D01*
X204526Y197535D01*
X204429Y197313D01*
X204360Y197063D01*
X204332Y196924D01*
Y196703D01*
X204346Y196647D01*
X204360Y196495D01*
X204415Y196314D01*
X204485Y196092D01*
X204610Y195857D01*
X204762Y195621D01*
X204873Y195510D01*
X204984Y195399D01*
X204998D01*
X205012Y195371D01*
X205053Y195343D01*
X205095Y195316D01*
X205234Y195219D01*
X205428Y195122D01*
X205664Y195011D01*
X205955Y194914D01*
X206288Y194858D01*
X206648Y194830D01*
X206662D01*
X206690D01*
X206731D01*
X206801Y194844D01*
X206884D01*
X206967Y194858D01*
X207175Y194900D01*
X207411Y194969D01*
X207661Y195052D01*
X207910Y195191D01*
X208132Y195371D01*
X208160Y195399D01*
X208215Y195468D01*
X208312Y195593D01*
X208410Y195746D01*
X208521Y195954D01*
X208618Y196189D01*
X208673Y196453D01*
X208701Y196744D01*
Y196827D01*
X208687Y196883D01*
X208673Y197035D01*
X208631Y197216D01*
X208562Y197438D01*
X208465Y197659D01*
X208326Y197881D01*
X208132Y198089D01*
X208104Y198117D01*
X208021Y198173D01*
X207896Y198256D01*
X207716Y198367D01*
X207494Y198464D01*
X207231Y198547D01*
X206912Y198603D01*
X206551Y198630D01*
D02*
G37*
G36*
X208215Y175525D02*
X208202D01*
X208160D01*
X208104D01*
X208021D01*
X207924Y175512D01*
X207799D01*
X207675Y175498D01*
X207522Y175470D01*
X207203Y175429D01*
X206870Y175359D01*
X206510Y175262D01*
X206177Y175123D01*
X206163D01*
X206135Y175110D01*
X206094Y175082D01*
X206038Y175054D01*
X205872Y174957D01*
X205678Y174832D01*
X205456Y174666D01*
X205234Y174458D01*
X205012Y174222D01*
X204818Y173958D01*
Y173944D01*
X204790Y173931D01*
X204776Y173889D01*
X204734Y173820D01*
X204707Y173750D01*
X204665Y173667D01*
X204568Y173459D01*
X204485Y173209D01*
X204402Y172918D01*
X204346Y172585D01*
X204332Y172239D01*
Y172114D01*
X204346Y172017D01*
X204360Y171892D01*
X204388Y171767D01*
X204415Y171615D01*
X204443Y171448D01*
X204554Y171088D01*
X204637Y170893D01*
X204721Y170699D01*
X204832Y170491D01*
X204956Y170297D01*
X205095Y170103D01*
X205261Y169923D01*
X205275Y169909D01*
X205303Y169881D01*
X205359Y169839D01*
X205442Y169770D01*
X205539Y169701D01*
X205664Y169618D01*
X205816Y169534D01*
X205996Y169437D01*
X206191Y169354D01*
X206426Y169257D01*
X206676Y169174D01*
X206953Y169104D01*
X207258Y169035D01*
X207605Y168993D01*
X207966Y168966D01*
X208354Y168952D01*
X208368D01*
X208423D01*
X208521D01*
X208645Y168966D01*
X208784Y168980D01*
X208950Y169007D01*
X209145Y169035D01*
X209339Y169063D01*
X209783Y169174D01*
X210004Y169257D01*
X210240Y169340D01*
X210462Y169451D01*
X210684Y169576D01*
X210892Y169715D01*
X211086Y169881D01*
X211100Y169895D01*
X211128Y169923D01*
X211183Y169978D01*
X211239Y170047D01*
X211322Y170145D01*
X211405Y170256D01*
X211488Y170380D01*
X211585Y170519D01*
X211682Y170686D01*
X211766Y170866D01*
X211849Y171060D01*
X211932Y171268D01*
X211988Y171490D01*
X212043Y171712D01*
X212071Y171961D01*
X212085Y172225D01*
Y172294D01*
X212071Y172363D01*
Y172461D01*
X212057Y172585D01*
X212029Y172724D01*
X212001Y172890D01*
X211960Y173057D01*
X211904Y173251D01*
X211835Y173431D01*
X211766Y173639D01*
X211669Y173834D01*
X211544Y174028D01*
X211419Y174222D01*
X211266Y174416D01*
X211086Y174596D01*
X211072Y174610D01*
X211045Y174638D01*
X210975Y174680D01*
X210892Y174749D01*
X210795Y174818D01*
X210670Y174888D01*
X210518Y174971D01*
X210351Y175068D01*
X210157Y175151D01*
X209935Y175234D01*
X209699Y175304D01*
X209450Y175387D01*
X209172Y175442D01*
X208867Y175484D01*
X208548Y175512D01*
X208215Y175525D01*
D02*
G37*
G36*
X85862Y111207D02*
X85855D01*
X85841D01*
X85813D01*
X85778Y111199D01*
X85735D01*
X85686Y111192D01*
X85573Y111171D01*
X85447Y111143D01*
X85313Y111094D01*
X85186Y111024D01*
X85067Y110932D01*
X85053Y110918D01*
X85018Y110883D01*
X84975Y110827D01*
X84919Y110749D01*
X84863Y110651D01*
X84821Y110538D01*
X84785Y110404D01*
X84771Y110257D01*
Y110214D01*
X84778Y110186D01*
X84785Y110116D01*
X84806Y110017D01*
X84842Y109912D01*
X84898Y109792D01*
X84968Y109680D01*
X85067Y109567D01*
X85081Y109553D01*
X85116Y109525D01*
X85179Y109476D01*
X85271Y109426D01*
X85376Y109377D01*
X85510Y109328D01*
X85658Y109300D01*
X85827Y109286D01*
X85841D01*
X85876D01*
X85939Y109293D01*
X86017Y109300D01*
X86108Y109314D01*
X86207Y109342D01*
X86312Y109370D01*
X86418Y109412D01*
X86432Y109419D01*
X86467Y109440D01*
X86516Y109469D01*
X86580Y109511D01*
X86643Y109560D01*
X86720Y109623D01*
X86784Y109694D01*
X86847Y109778D01*
X86854Y109792D01*
X86868Y109820D01*
X86896Y109870D01*
X86917Y109933D01*
X86945Y110003D01*
X86973Y110088D01*
X86988Y110179D01*
X86995Y110278D01*
Y110313D01*
X86988Y110341D01*
X86981Y110411D01*
X86959Y110503D01*
X86917Y110601D01*
X86868Y110714D01*
X86791Y110827D01*
X86748Y110883D01*
X86692Y110932D01*
X86685D01*
X86678Y110946D01*
X86636Y110974D01*
X86566Y111017D01*
X86474Y111073D01*
X86354Y111122D01*
X86214Y111164D01*
X86052Y111192D01*
X85862Y111207D01*
D02*
G37*
G36*
X83871Y103411D02*
X83864D01*
X83857D01*
X83814Y103404D01*
X83751Y103397D01*
X83667Y103383D01*
X83582Y103348D01*
X83484Y103305D01*
X83392Y103242D01*
X83301Y103158D01*
X83294Y103144D01*
X83266Y103108D01*
X83230Y103052D01*
X83188Y102961D01*
X83146Y102855D01*
X83111Y102714D01*
X83083Y102552D01*
X83076Y102362D01*
Y100829D01*
X84687D01*
Y102278D01*
X84680Y102362D01*
X84673Y102461D01*
X84666Y102574D01*
X84652Y102686D01*
X84631Y102799D01*
X84602Y102897D01*
X84595Y102911D01*
X84581Y102939D01*
X84560Y102982D01*
X84532Y103038D01*
X84490Y103101D01*
X84441Y103165D01*
X84377Y103228D01*
X84307Y103277D01*
X84300Y103284D01*
X84272Y103298D01*
X84230Y103319D01*
X84173Y103348D01*
X84110Y103369D01*
X84040Y103390D01*
X83955Y103404D01*
X83871Y103411D01*
D02*
G37*
G36*
X99913Y114882D02*
X99906D01*
X99899D01*
X99857Y114875D01*
X99793Y114868D01*
X99709Y114854D01*
X99625Y114819D01*
X99526Y114777D01*
X99434Y114713D01*
X99343Y114629D01*
X99336Y114615D01*
X99308Y114580D01*
X99273Y114523D01*
X99230Y114432D01*
X99188Y114326D01*
X99153Y114186D01*
X99125Y114024D01*
X99118Y113834D01*
Y112300D01*
X100729D01*
Y113750D01*
X100722Y113834D01*
X100715Y113932D01*
X100708Y114045D01*
X100694Y114158D01*
X100673Y114270D01*
X100645Y114369D01*
X100638Y114383D01*
X100624Y114411D01*
X100602Y114453D01*
X100574Y114509D01*
X100532Y114573D01*
X100483Y114636D01*
X100420Y114699D01*
X100349Y114749D01*
X100342Y114756D01*
X100314Y114770D01*
X100272Y114791D01*
X100216Y114819D01*
X100152Y114840D01*
X100082Y114861D01*
X99997Y114875D01*
X99913Y114882D01*
D02*
G37*
G36*
X110275Y147459D02*
X110269D01*
X110258D01*
X110234D01*
X110205Y147453D01*
X110164D01*
X110123Y147448D01*
X110029Y147430D01*
X109917Y147406D01*
X109800Y147365D01*
X109689Y147307D01*
X109589Y147230D01*
X109583D01*
X109577Y147219D01*
X109548Y147189D01*
X109507Y147142D01*
X109460Y147078D01*
X109419Y146996D01*
X109378Y146902D01*
X109348Y146796D01*
X109337Y146737D01*
Y146644D01*
X109342Y146620D01*
X109348Y146556D01*
X109372Y146479D01*
X109401Y146385D01*
X109454Y146286D01*
X109518Y146186D01*
X109565Y146139D01*
X109612Y146092D01*
X109618D01*
X109624Y146080D01*
X109642Y146069D01*
X109659Y146057D01*
X109718Y146016D01*
X109800Y145975D01*
X109900Y145928D01*
X110023Y145887D01*
X110164Y145863D01*
X110316Y145851D01*
X110322D01*
X110334D01*
X110352D01*
X110381Y145857D01*
X110416D01*
X110451Y145863D01*
X110539Y145881D01*
X110639Y145910D01*
X110745Y145945D01*
X110850Y146004D01*
X110944Y146080D01*
X110956Y146092D01*
X110979Y146122D01*
X111020Y146174D01*
X111062Y146239D01*
X111109Y146327D01*
X111150Y146427D01*
X111173Y146538D01*
X111185Y146661D01*
Y146697D01*
X111179Y146720D01*
X111173Y146784D01*
X111156Y146861D01*
X111126Y146955D01*
X111085Y147049D01*
X111026Y147142D01*
X110944Y147230D01*
X110933Y147242D01*
X110897Y147266D01*
X110844Y147301D01*
X110768Y147348D01*
X110674Y147389D01*
X110563Y147424D01*
X110428Y147448D01*
X110275Y147459D01*
D02*
G37*
G36*
X110140Y144308D02*
X110135D01*
X110129D01*
X110099D01*
X110047Y144303D01*
X109988Y144291D01*
X109923Y144279D01*
X109847Y144256D01*
X109777Y144220D01*
X109706Y144179D01*
X109700Y144173D01*
X109677Y144156D01*
X109648Y144127D01*
X109607Y144091D01*
X109565Y144038D01*
X109530Y143980D01*
X109495Y143915D01*
X109466Y143839D01*
Y143833D01*
X109460Y143810D01*
X109454Y143774D01*
X109442Y143728D01*
X109436Y143657D01*
X109431Y143569D01*
X109425Y143463D01*
Y142302D01*
X110874D01*
Y143393D01*
X110868Y143434D01*
Y143475D01*
X110862Y143522D01*
X110850Y143634D01*
X110827Y143757D01*
X110792Y143880D01*
X110745Y143992D01*
X110715Y144044D01*
X110680Y144086D01*
X110668Y144097D01*
X110645Y144121D01*
X110598Y144156D01*
X110539Y144197D01*
X110463Y144238D01*
X110369Y144273D01*
X110264Y144297D01*
X110140Y144308D01*
D02*
G37*
G36*
X95988Y148336D02*
X95982D01*
X95976D01*
X95941D01*
X95888Y148324D01*
X95824Y148313D01*
X95753Y148289D01*
X95677Y148254D01*
X95601Y148207D01*
X95524Y148142D01*
X95519Y148137D01*
X95495Y148107D01*
X95466Y148066D01*
X95430Y148013D01*
X95395Y147943D01*
X95366Y147867D01*
X95343Y147773D01*
X95337Y147673D01*
Y147626D01*
X95348Y147573D01*
X95360Y147503D01*
X95384Y147427D01*
X95413Y147344D01*
X95460Y147268D01*
X95524Y147192D01*
X95530Y147186D01*
X95554Y147163D01*
X95595Y147133D01*
X95648Y147104D01*
X95712Y147069D01*
X95788Y147039D01*
X95871Y147016D01*
X95964Y147010D01*
X95970D01*
X95976D01*
X96011Y147016D01*
X96064Y147022D01*
X96129Y147033D01*
X96205Y147057D01*
X96281Y147086D01*
X96363Y147133D01*
X96434Y147192D01*
X96440Y147198D01*
X96463Y147227D01*
X96493Y147268D01*
X96522Y147321D01*
X96557Y147391D01*
X96586Y147473D01*
X96610Y147567D01*
X96616Y147673D01*
Y147685D01*
X96610Y147720D01*
X96604Y147773D01*
X96592Y147843D01*
X96569Y147919D01*
X96539Y147996D01*
X96493Y148078D01*
X96434Y148148D01*
X96428Y148154D01*
X96399Y148178D01*
X96363Y148207D01*
X96311Y148242D01*
X96246Y148277D01*
X96170Y148307D01*
X96082Y148330D01*
X95988Y148336D01*
D02*
G37*
G36*
X97854Y148500D02*
X97848D01*
X97836D01*
X97818D01*
X97795Y148494D01*
X97731Y148489D01*
X97642Y148471D01*
X97555Y148442D01*
X97455Y148400D01*
X97355Y148342D01*
X97261Y148260D01*
X97249Y148248D01*
X97226Y148219D01*
X97185Y148166D01*
X97138Y148095D01*
X97097Y148007D01*
X97056Y147902D01*
X97032Y147785D01*
X97021Y147655D01*
Y147620D01*
X97026Y147597D01*
X97032Y147532D01*
X97050Y147450D01*
X97079Y147356D01*
X97120Y147262D01*
X97179Y147163D01*
X97255Y147074D01*
X97267Y147063D01*
X97296Y147039D01*
X97349Y147004D01*
X97414Y146963D01*
X97502Y146916D01*
X97601Y146881D01*
X97713Y146857D01*
X97836Y146846D01*
X97848D01*
X97871D01*
X97912Y146852D01*
X97965Y146857D01*
X98030Y146869D01*
X98100Y146887D01*
X98170Y146910D01*
X98247Y146940D01*
X98253Y146945D01*
X98282Y146957D01*
X98317Y146981D01*
X98358Y147016D01*
X98411Y147057D01*
X98464Y147110D01*
X98511Y147168D01*
X98558Y147239D01*
X98564Y147250D01*
X98575Y147274D01*
X98593Y147315D01*
X98611Y147368D01*
X98628Y147432D01*
X98646Y147509D01*
X98658Y147591D01*
X98663Y147673D01*
Y147708D01*
X98658Y147732D01*
X98652Y147802D01*
X98634Y147884D01*
X98605Y147978D01*
X98569Y148078D01*
X98511Y148172D01*
X98435Y148266D01*
X98423Y148277D01*
X98393Y148301D01*
X98341Y148342D01*
X98276Y148383D01*
X98194Y148424D01*
X98094Y148465D01*
X97977Y148489D01*
X97854Y148500D01*
D02*
G37*
G36*
X96140Y145308D02*
X96135D01*
X96129D01*
X96099D01*
X96046Y145303D01*
X95988Y145291D01*
X95923Y145279D01*
X95847Y145256D01*
X95777Y145220D01*
X95706Y145179D01*
X95700Y145174D01*
X95677Y145156D01*
X95648Y145126D01*
X95606Y145091D01*
X95565Y145038D01*
X95530Y144980D01*
X95495Y144915D01*
X95466Y144839D01*
Y144833D01*
X95460Y144810D01*
X95454Y144775D01*
X95442Y144727D01*
X95436Y144657D01*
X95430Y144569D01*
X95425Y144464D01*
Y143302D01*
X96874D01*
Y144393D01*
X96868Y144434D01*
Y144475D01*
X96862Y144522D01*
X96850Y144634D01*
X96827Y144757D01*
X96792Y144880D01*
X96745Y144992D01*
X96715Y145044D01*
X96680Y145085D01*
X96669Y145097D01*
X96645Y145121D01*
X96598Y145156D01*
X96539Y145197D01*
X96463Y145238D01*
X96369Y145273D01*
X96264Y145297D01*
X96140Y145308D01*
D02*
G37*
%LPD*%
D10*
X52250Y373000D02*
G03*
X52250Y373000I-1250J0D01*
G01*
D11*
X127654Y338220D02*
G03*
X127654Y338220I-762J0D01*
G01*
X79033Y132070D02*
Y160010D01*
Y132070D02*
X91734D01*
Y160010D01*
X79033D02*
X91734D01*
X54046Y337142D02*
X79954D01*
X54046D02*
Y350858D01*
X79954D01*
Y337142D02*
Y350858D01*
X155094Y334666D02*
Y345334D01*
X174906D01*
Y334666D02*
Y345334D01*
X155094Y334666D02*
X174906D01*
X133970Y81650D02*
Y94350D01*
X106030Y81650D02*
X133970D01*
X106030D02*
Y94350D01*
X133970D01*
X28750Y167245D02*
X189250D01*
X28750Y310755D02*
X189250D01*
X28750Y167245D02*
Y310755D01*
X189250Y167245D02*
Y310755D01*
X55094Y364826D02*
X74906D01*
X55094Y355174D02*
Y364826D01*
X74906Y355174D02*
Y364826D01*
X55094Y355174D02*
X74906D01*
X164094Y164826D02*
X183906D01*
X164094Y155174D02*
Y164826D01*
X183906Y155174D02*
Y164826D01*
X164094Y155174D02*
X183906D01*
X164094Y152826D02*
X183906D01*
X164094Y143174D02*
Y152826D01*
X183906Y143174D02*
Y152826D01*
X164094Y143174D02*
X183906D01*
X164094Y140826D02*
X183906D01*
X164094Y131174D02*
Y140826D01*
X183906Y131174D02*
Y140826D01*
X164094Y131174D02*
X183906D01*
X34174Y333094D02*
Y352906D01*
Y333094D02*
X43826D01*
X34174Y352906D02*
X43826D01*
Y333094D02*
Y352906D01*
X109906Y318666D02*
Y329334D01*
X90094Y318666D02*
X109906D01*
X90094D02*
Y329334D01*
X109906D01*
X60666Y78906D02*
X71334D01*
Y59094D02*
Y78906D01*
X60666Y59094D02*
X71334D01*
X60666D02*
Y78906D01*
X46666D02*
X57334D01*
Y59094D02*
Y78906D01*
X46666Y59094D02*
X57334D01*
X46666D02*
Y78906D01*
X184666Y349906D02*
X195334D01*
Y330094D02*
Y349906D01*
X184666Y330094D02*
X195334D01*
X184666D02*
Y349906D01*
X135666Y346094D02*
X146334D01*
X135666D02*
Y365906D01*
X146334D01*
Y346094D02*
Y365906D01*
X174906Y354666D02*
Y365334D01*
X155094Y354666D02*
X174906D01*
X155094D02*
Y365334D01*
X174906D01*
X55089Y164174D02*
Y157826D01*
X59321D01*
X65669Y164174D02*
X61437D01*
Y157826D01*
X65669D01*
X61437Y161000D02*
X63553D01*
X67785Y164174D02*
Y157826D01*
X70959D01*
X72017Y158884D01*
Y163116D01*
X70959Y164174D01*
X67785D01*
X74133Y157826D02*
X76249D01*
X75191D01*
Y164174D01*
X74133Y163116D01*
X118000Y378884D02*
Y383116D01*
X116942Y384174D01*
X114826D01*
X113768Y383116D01*
Y378884D01*
X114826Y377826D01*
X116942D01*
X115884Y379942D02*
X118000Y377826D01*
X116942D02*
X118000Y378884D01*
X120116Y377826D02*
X122232D01*
X121174D01*
Y384174D01*
X120116Y383116D01*
X63992Y373116D02*
X62934Y374174D01*
X60818D01*
X59760Y373116D01*
Y368884D01*
X60818Y367826D01*
X62934D01*
X63992Y368884D01*
X70340Y374174D02*
X66108D01*
Y371000D01*
X68224Y372058D01*
X69282D01*
X70340Y371000D01*
Y368884D01*
X69282Y367826D01*
X67166D01*
X66108Y368884D01*
X15768Y175174D02*
Y169884D01*
X16826Y168826D01*
X18942D01*
X20000Y169884D01*
Y175174D01*
X22116Y168826D02*
X24232D01*
X23174D01*
Y175174D01*
X22116Y174116D01*
X146820Y146626D02*
Y142394D01*
Y144510D01*
X140472D01*
Y140278D02*
X146820D01*
Y137104D01*
X145762Y136046D01*
X143646D01*
X142588Y137104D01*
Y140278D01*
X140472Y133930D02*
Y131814D01*
Y132872D01*
X146820D01*
X145762Y133930D01*
X140472Y128640D02*
Y126524D01*
Y127582D01*
X146820D01*
X145762Y128640D01*
X159500Y161159D02*
Y156927D01*
Y159043D01*
X153153D01*
Y154811D02*
X159500D01*
Y151637D01*
X158442Y150579D01*
X156327D01*
X155268Y151637D01*
Y154811D01*
X153153Y148463D02*
Y146347D01*
Y147405D01*
X159500D01*
X158442Y148463D01*
Y143173D02*
X159500Y142115D01*
Y139999D01*
X158442Y138941D01*
X154211D01*
X153153Y139999D01*
Y142115D01*
X154211Y143173D01*
X158442D01*
X193536Y291174D02*
X197768D01*
X195652D01*
Y284826D01*
X199884D02*
Y291174D01*
X203058D01*
X204116Y290116D01*
Y288000D01*
X203058Y286942D01*
X199884D01*
X206232Y291174D02*
X210464D01*
Y290116D01*
X206232Y285884D01*
Y284826D01*
X170886Y389174D02*
X175118D01*
X173002D01*
Y382826D01*
X177234D02*
Y389174D01*
X180408D01*
X181466Y388116D01*
Y386000D01*
X180408Y384942D01*
X177234D01*
X187814Y389174D02*
X185698Y388116D01*
X183582Y386000D01*
Y383884D01*
X184640Y382826D01*
X186756D01*
X187814Y383884D01*
Y384942D01*
X186756Y386000D01*
X183582D01*
X134536Y342174D02*
X138768D01*
X136652D01*
Y335826D01*
X140884D02*
Y342174D01*
X144058D01*
X145116Y341116D01*
Y339000D01*
X144058Y337942D01*
X140884D01*
X151464Y342174D02*
X147232D01*
Y339000D01*
X149348Y340058D01*
X150406D01*
X151464Y339000D01*
Y336884D01*
X150406Y335826D01*
X148290D01*
X147232Y336884D01*
X124066Y331726D02*
X128298D01*
X126182D01*
Y325378D01*
X130414D02*
Y331726D01*
X133588D01*
X134646Y330668D01*
Y328552D01*
X133588Y327494D01*
X130414D01*
X139936Y325378D02*
Y331726D01*
X136762Y328552D01*
X140994D01*
X184594Y323472D02*
X188826D01*
X186710D01*
Y317124D01*
X190942D02*
Y323472D01*
X194116D01*
X195174Y322414D01*
Y320298D01*
X194116Y319240D01*
X190942D01*
X197290Y317124D02*
X199406D01*
X198348D01*
Y323472D01*
X197290Y322414D01*
X200826Y347435D02*
X207174D01*
Y344261D01*
X206116Y343203D01*
X204000D01*
X202942Y344261D01*
Y347435D01*
Y345319D02*
X200826Y343203D01*
Y341087D02*
Y338971D01*
Y340029D01*
X207174D01*
X206116Y341087D01*
Y335797D02*
X207174Y334739D01*
Y332623D01*
X206116Y331565D01*
X201884D01*
X200826Y332623D01*
Y334739D01*
X201884Y335797D01*
X206116D01*
X48826Y94960D02*
X55174D01*
Y91786D01*
X54116Y90729D01*
X52000D01*
X50942Y91786D01*
Y94960D01*
Y92844D02*
X48826Y90729D01*
X54116Y88613D02*
X55174Y87555D01*
Y85439D01*
X54116Y84381D01*
X53058D01*
X52000Y85439D01*
X50942Y84381D01*
X49884D01*
X48826Y85439D01*
Y87555D01*
X49884Y88613D01*
X50942D01*
X52000Y87555D01*
X53058Y88613D01*
X54116D01*
X52000Y87555D02*
Y85439D01*
X62826Y94805D02*
X69174D01*
Y91631D01*
X68116Y90573D01*
X66000D01*
X64942Y91631D01*
Y94805D01*
Y92689D02*
X62826Y90573D01*
X69174Y84225D02*
Y88457D01*
X66000D01*
X67058Y86341D01*
Y85283D01*
X66000Y84225D01*
X63884D01*
X62826Y85283D01*
Y87399D01*
X63884Y88457D01*
X72290Y333174D02*
Y326826D01*
X69116D01*
X68058Y327884D01*
Y330000D01*
X69116Y331058D01*
X72290D01*
X70174D02*
X68058Y333174D01*
X62768D02*
Y326826D01*
X65942Y330000D01*
X61710D01*
X99710Y97826D02*
Y104174D01*
X102884D01*
X103942Y103116D01*
Y101000D01*
X102884Y99942D01*
X99710D01*
X101826D02*
X103942Y97826D01*
X106058Y103116D02*
X107116Y104174D01*
X109232D01*
X110290Y103116D01*
Y102058D01*
X109232Y101000D01*
X108174D01*
X109232D01*
X110290Y99942D01*
Y98884D01*
X109232Y97826D01*
X107116D01*
X106058Y98884D01*
X87768Y332826D02*
Y339174D01*
X90942D01*
X92000Y338116D01*
Y336000D01*
X90942Y334942D01*
X87768D01*
X89884D02*
X92000Y332826D01*
X94116D02*
X96232D01*
X95174D01*
Y339174D01*
X94116Y338116D01*
X109862Y78174D02*
Y71826D01*
X114094D01*
X120442Y78174D02*
X116210D01*
Y71826D01*
X120442D01*
X116210Y75000D02*
X118326D01*
X122558Y78174D02*
Y71826D01*
X125732D01*
X126790Y72884D01*
Y77116D01*
X125732Y78174D01*
X122558D01*
X133138Y71826D02*
X128906D01*
X133138Y76058D01*
Y77116D01*
X132080Y78174D01*
X129964D01*
X128906Y77116D01*
X18768Y364174D02*
Y357826D01*
X23000D01*
X25116D02*
X27232D01*
X26174D01*
Y364174D01*
X25116Y363116D01*
X70078Y397693D02*
Y401078D01*
Y399386D01*
X61614D01*
X59922Y401078D01*
Y402771D01*
X61614Y404464D01*
X59922Y387536D02*
Y394307D01*
X66693Y387536D01*
X68386D01*
X70078Y389229D01*
Y392614D01*
X68386Y394307D01*
X193310Y38174D02*
X191194D01*
X192252D01*
Y32884D01*
X191194Y31826D01*
X190136D01*
X189078Y32884D01*
X195426Y31826D02*
X197542D01*
X196484D01*
Y38174D01*
X195426Y37116D01*
X24834Y341450D02*
X23776Y340392D01*
Y338276D01*
X24834Y337218D01*
X29066D01*
X30124Y338276D01*
Y340392D01*
X29066Y341450D01*
X30124Y346740D02*
X23776D01*
X26950Y343566D01*
Y347798D01*
X191473Y138116D02*
X190415Y139174D01*
X188299D01*
X187241Y138116D01*
Y133884D01*
X188299Y132826D01*
X190415D01*
X191473Y133884D01*
X193589Y138116D02*
X194647Y139174D01*
X196763D01*
X197821Y138116D01*
Y137058D01*
X196763Y136000D01*
X195705D01*
X196763D01*
X197821Y134942D01*
Y133884D01*
X196763Y132826D01*
X194647D01*
X193589Y133884D01*
X190942Y150116D02*
X189884Y151174D01*
X187768D01*
X186710Y150116D01*
Y145884D01*
X187768Y144826D01*
X189884D01*
X190942Y145884D01*
X197290Y144826D02*
X193058D01*
X197290Y149058D01*
Y150116D01*
X196232Y151174D01*
X194116D01*
X193058Y150116D01*
X192000Y162116D02*
X190942Y163174D01*
X188826D01*
X187768Y162116D01*
Y157884D01*
X188826Y156826D01*
X190942D01*
X192000Y157884D01*
X194116Y156826D02*
X196232D01*
X195174D01*
Y163174D01*
X194116Y162116D01*
D12*
X76000Y116000D02*
Y120000D01*
Y124000D02*
Y128000D01*
X72000Y120000D02*
X80000D01*
X76000Y124000D02*
X80000Y120000D01*
X76000Y124000D02*
Y124000D01*
X72000Y120000D02*
X76000Y124000D01*
D13*
X50500Y129500D02*
Y150500D01*
X75500Y129500D02*
Y150500D01*
X36638Y353250D02*
X49362D01*
X36638Y366750D02*
X49362D01*
X28250Y412750D02*
X39750D01*
X169015Y105000D02*
X176985D01*
X169015Y87000D02*
X176985D01*
X169015Y128000D02*
X176985D01*
X169015Y110000D02*
X176985D01*
D14*
X85320Y146865D02*
X86463Y145722D01*
X84177D02*
X85320Y146865D01*
X84177Y145722D02*
X86463D01*
X119683Y86920D02*
Y89206D01*
X120826Y88063D01*
X119683Y86920D02*
X120826Y88063D01*
D15*
X130194Y341516D02*
Y370484D01*
X102127Y338474D02*
Y350666D01*
X93110D02*
X102127D01*
X93110D02*
Y361334D01*
X102127D01*
Y373526D01*
X121177D01*
Y370484D02*
Y373526D01*
Y370484D02*
X130194D01*
X121177Y338474D02*
Y341516D01*
X102127Y338474D02*
X121177D01*
Y341516D02*
X130194D01*
D16*
X201060Y27500D02*
Y29166D01*
Y28333D01*
X206058D01*
X205225Y27500D01*
X151750Y31582D02*
Y28250D01*
X155082Y31582D01*
X155915D01*
X156748Y30749D01*
Y29083D01*
X155915Y28250D01*
X151750Y33248D02*
Y34915D01*
Y34081D01*
X156748D01*
X155915Y33248D01*
X175000Y27750D02*
Y29416D01*
Y28583D01*
X179998D01*
X179165Y27750D01*
X175000Y31916D02*
Y33582D01*
Y32749D01*
X179998D01*
X179165Y31916D01*
X19998Y29000D02*
Y32332D01*
X19165D01*
X15833Y29000D01*
X15000D01*
X19998Y37331D02*
Y33998D01*
X17499D01*
X18332Y35665D01*
Y36497D01*
X17499Y37331D01*
X15833D01*
X15000Y36497D01*
Y34831D01*
X15833Y33998D01*
D17*
X152540Y51697D02*
Y44079D01*
X156349D01*
X157618Y45349D01*
Y46618D01*
X156349Y47888D01*
X152540D01*
X156349D01*
X157618Y49158D01*
Y50427D01*
X156349Y51697D01*
X152540D01*
X167775D02*
Y44079D01*
Y46618D01*
X172853Y51697D01*
X169045Y47888D01*
X172853Y44079D01*
X179201D02*
X176662D01*
X175393Y45349D01*
Y47888D01*
X176662Y49158D01*
X179201D01*
X180471Y47888D01*
Y46618D01*
X175393D01*
X183010Y49158D02*
Y45349D01*
X184280Y44079D01*
X188088D01*
Y42810D01*
X186819Y41540D01*
X185549D01*
X188088Y44079D02*
Y49158D01*
X89191Y78502D02*
X96809D01*
Y74693D01*
X95539Y73424D01*
X93000D01*
X91730Y74693D01*
Y78502D01*
Y75963D02*
X89191Y73424D01*
Y70884D02*
Y68345D01*
Y69615D01*
X96809D01*
X95539Y70884D01*
Y64536D02*
X96809Y63267D01*
Y60728D01*
X95539Y59458D01*
X94270D01*
X93000Y60728D01*
Y61997D01*
Y60728D01*
X91730Y59458D01*
X90461D01*
X89191Y60728D01*
Y63267D01*
X90461Y64536D01*
X33191Y103522D02*
X40809D01*
Y99713D01*
X39539Y98443D01*
X37000D01*
X35730Y99713D01*
Y103522D01*
Y100983D02*
X33191Y98443D01*
Y95904D02*
Y93365D01*
Y94635D01*
X40809D01*
X39539Y95904D01*
X33191Y84478D02*
Y89556D01*
X38270Y84478D01*
X39539D01*
X40809Y85748D01*
Y88287D01*
X39539Y89556D01*
X131809Y117652D02*
X124191D01*
Y121461D01*
X125461Y122730D01*
X128000D01*
X129270Y121461D01*
Y117652D01*
Y120191D02*
X131809Y122730D01*
Y130348D02*
Y125270D01*
X126730Y130348D01*
X125461D01*
X124191Y129078D01*
Y126539D01*
X125461Y125270D01*
X143730Y98539D02*
X142461Y99809D01*
X139922D01*
X138652Y98539D01*
Y93461D01*
X139922Y92191D01*
X142461D01*
X143730Y93461D01*
X146270Y99809D02*
X151348D01*
Y98539D01*
X146270Y93461D01*
Y92191D01*
X142730Y120539D02*
X141461Y121809D01*
X138922D01*
X137652Y120539D01*
Y115461D01*
X138922Y114191D01*
X141461D01*
X142730Y115461D01*
X150348Y121809D02*
X147809Y120539D01*
X145270Y118000D01*
Y115461D01*
X146539Y114191D01*
X149078D01*
X150348Y115461D01*
Y116730D01*
X149078Y118000D01*
X145270D01*
D18*
X151710Y368826D02*
Y375174D01*
X154884D01*
X155942Y374116D01*
Y372000D01*
X154884Y370942D01*
X151710D01*
X153826D02*
X155942Y368826D01*
X158058Y369884D02*
X159116Y368826D01*
X161232D01*
X162290Y369884D01*
Y374116D01*
X161232Y375174D01*
X159116D01*
X158058Y374116D01*
Y373058D01*
X159116Y372000D01*
X162290D01*
X151710Y378826D02*
Y385174D01*
X154884D01*
X155942Y384116D01*
Y382000D01*
X154884Y380942D01*
X151710D01*
X153826D02*
X155942Y378826D01*
X158058Y385174D02*
X162290D01*
Y384116D01*
X158058Y379884D01*
Y378826D01*
X143174Y370710D02*
X136826D01*
Y373884D01*
X137884Y374942D01*
X140000D01*
X141058Y373884D01*
Y370710D01*
Y372826D02*
X143174Y374942D01*
X136826Y381290D02*
X137884Y379174D01*
X140000Y377058D01*
X142116D01*
X143174Y378116D01*
Y380232D01*
X142116Y381290D01*
X141058D01*
X140000Y380232D01*
Y377058D01*
D19*
X85364Y146065D02*
D03*
D20*
X120025Y88023D02*
D03*
D21*
X187000Y293377D02*
D03*
M02*
